FILE_TYPE = MACRO_DRAWING;
SET COLOR_WIRE YELLOW;
SET COLOR_PROP ORANGE;
SET COLOR_DOT WHITE;
SET COLOR_ARC YELLOW;
SET COLOR_BODY GREEN;
SET COLOR_NOTE PURPLE;
SET PROP_DISPLAY VALUE;
SET PAGE_NUMBER P377;
FORCEADD UNIVERSAL_GND..1
(-8525 875);
FORCEPROP 3 LASTPIN (-8525 925) SIG_NAME GND\g
J 0
(-8515 935);
DISPLAY 0.659574 (-8515 935);
PAINT MONO (-8515 935);
DISPLAY INVISIBLE (-8515 935);
FORCEPROP 2 LAST CDS_LIB pure_quanta_power
J 0
(-8525 875);
DISPLAY INVISIBLE (-8525 875);
FORCEPROP 1 LAST HDL_POWER GND
J 1
(-8500 800);
DISPLAY 0.872340 (-8500 800);
PAINT GREEN (-8500 800);
DISPLAY INVISIBLE (-8500 800);
FORCEPROP 1 LAST PATH I1
J 0
(-8450 875);
DISPLAY 0.872340 (-8450 875);
PAINT AQUA (-8450 875);
DISPLAY INVISIBLE (-8450 875);
FORCEADD OFFPAGE..5
R 2
(-6975 1550);
FORCEPROP 2 LAST $XR0 185 
J 0
(-6786 1550);
DISPLAY 0.638298 (-6786 1550);
PAINT MONO (-6786 1550);
FORCEPROP 2 LAST CDS_LIB standard
J 0
(-6975 1550);
DISPLAY INVISIBLE (-6975 1550);
FORCEPROP 1 LAST OFFPAGE TRUE
J 2
(-7300 1425);
DISPLAY 0.872340 (-7300 1425);
PAINT GREEN (-7300 1425);
DISPLAY INVISIBLE (-7300 1425);
FORCEPROP 1 LAST COMMENT_BODY TRUE
J 2
(-7075 1475);
DISPLAY 0.872340 (-7075 1475);
PAINT GREEN (-7075 1475);
DISPLAY INVISIBLE (-7075 1475);
FORCEPROP 2 LAST PATH I10
J 0
(-6775 1600);
DISPLAY 0.680851 (-6775 1600);
DISPLAY INVISIBLE (-6775 1600);
FORCEADD OFFPAGE..2
(-775 2425);
FORCEPROP 2 LAST $XR0 185 
J 0
(-586 2425);
DISPLAY 0.638298 (-586 2425);
PAINT MONO (-586 2425);
FORCEPROP 2 LAST CDS_LIB standard
J 0
(-775 2425);
DISPLAY INVISIBLE (-775 2425);
FORCEPROP 1 LAST OFFPAGE TRUE
J 0
(-450 2300);
DISPLAY 0.872340 (-450 2300);
PAINT GREEN (-450 2300);
DISPLAY INVISIBLE (-450 2300);
FORCEPROP 1 LAST COMMENT_BODY TRUE
J 0
(-820 2330);
DISPLAY 0.872340 (-820 2330);
PAINT GREEN (-820 2330);
DISPLAY INVISIBLE (-820 2330);
FORCEPROP 2 LAST PATH I100
J 0
(-600 2500);
DISPLAY 0.680851 (-600 2500);
DISPLAY INVISIBLE (-600 2500);
FORCEADD OFFPAGE..2
(-775 2375);
FORCEPROP 2 LAST $XR0 185 
J 0
(-586 2375);
DISPLAY 0.638298 (-586 2375);
PAINT MONO (-586 2375);
FORCEPROP 2 LAST CDS_LIB standard
J 0
(-775 2375);
DISPLAY INVISIBLE (-775 2375);
FORCEPROP 1 LAST OFFPAGE TRUE
J 0
(-450 2250);
DISPLAY 0.872340 (-450 2250);
PAINT GREEN (-450 2250);
DISPLAY INVISIBLE (-450 2250);
FORCEPROP 1 LAST COMMENT_BODY TRUE
J 0
(-820 2280);
DISPLAY 0.872340 (-820 2280);
PAINT GREEN (-820 2280);
DISPLAY INVISIBLE (-820 2280);
FORCEPROP 2 LAST PATH I101
J 0
(-600 2450);
DISPLAY 0.680851 (-600 2450);
DISPLAY INVISIBLE (-600 2450);
FORCEADD OFFPAGE..2
(-775 2325);
FORCEPROP 2 LAST $XR0 185 
J 0
(-586 2325);
DISPLAY 0.638298 (-586 2325);
PAINT MONO (-586 2325);
FORCEPROP 2 LAST CDS_LIB standard
J 0
(-775 2325);
DISPLAY INVISIBLE (-775 2325);
FORCEPROP 1 LAST OFFPAGE TRUE
J 0
(-450 2200);
DISPLAY 0.872340 (-450 2200);
PAINT GREEN (-450 2200);
DISPLAY INVISIBLE (-450 2200);
FORCEPROP 1 LAST COMMENT_BODY TRUE
J 0
(-820 2230);
DISPLAY 0.872340 (-820 2230);
PAINT GREEN (-820 2230);
DISPLAY INVISIBLE (-820 2230);
FORCEPROP 2 LAST PATH I102
J 0
(-600 2400);
DISPLAY 0.680851 (-600 2400);
DISPLAY INVISIBLE (-600 2400);
FORCEADD OFFPAGE..2
(-775 2275);
FORCEPROP 2 LAST $XR0 185 
J 0
(-586 2275);
DISPLAY 0.638298 (-586 2275);
PAINT MONO (-586 2275);
FORCEPROP 2 LAST CDS_LIB standard
J 0
(-775 2275);
DISPLAY INVISIBLE (-775 2275);
FORCEPROP 1 LAST OFFPAGE TRUE
J 0
(-450 2150);
DISPLAY 0.872340 (-450 2150);
PAINT GREEN (-450 2150);
DISPLAY INVISIBLE (-450 2150);
FORCEPROP 1 LAST COMMENT_BODY TRUE
J 0
(-820 2180);
DISPLAY 0.872340 (-820 2180);
PAINT GREEN (-820 2180);
DISPLAY INVISIBLE (-820 2180);
FORCEPROP 2 LAST PATH I103
J 0
(-600 2350);
DISPLAY 0.680851 (-600 2350);
DISPLAY INVISIBLE (-600 2350);
FORCEADD Q_RES..1
(-2400 2625);
FORCEPROP 1 LAST LOCATION R1361
J 0
(-2750 2625);
DISPLAY 0.787234 (-2750 2625);
FORCEPROP 2 LAST SEC 1
J 0
(-2125 2850);
DISPLAY 0.680851 (-2125 2850);
PAINT MONO (-2125 2850);
DISPLAY INVISIBLE (-2125 2850);
FORCEPROP 1 LASTPIN (-2500 2625) $PN 1
J 0
(-2488 2637);
DISPLAY 0.787234 (-2488 2637);
PAINT MONO (-2488 2637);
FORCEPROP 1 LASTPIN (-2300 2625) $PN 2
J 0
(-2338 2637);
DISPLAY 0.787234 (-2338 2637);
PAINT MONO (-2338 2637);
FORCEPROP 1 LAST PACK_TYPE 0201LF
J 0
(-1950 2625);
DISPLAY 0.638298 (-1950 2625);
FORCEPROP 1 LAST TOLERANCE 5%
J 0
(-2600 2800);
DISPLAY 0.978723 (-2600 2800);
FORCEPROP 1 LAST VALUE 4.7K
J 2
(-2125 2625);
DISPLAY 0.638298 (-2125 2625);
FORCEPROP 1 LAST WATTAGE 1/20W
J 2
(-2125 2800);
DISPLAY 0.978723 (-2125 2800);
FORCEPROP 1 LAST MATERIAL CHIP
J 0
(-2100 2625);
DISPLAY 0.638298 (-2100 2625);
FORCEPROP 2 LAST SEC_TYPE 0201LF
J 0
(-2125 2850);
DISPLAY 0.680851 (-2125 2850);
DISPLAY INVISIBLE (-2125 2850);
FORCEPROP 2 LAST CDS_LIB pure_quanta
J 0
(-2400 2625);
DISPLAY INVISIBLE (-2400 2625);
FORCEPROP 1 LAST PATH I104
J 0
(-2450 2775);
DISPLAY 0.978723 (-2450 2775);
PAINT WHITE (-2450 2775);
DISPLAY INVISIBLE (-2450 2775);
FORCEPROP 1 LAST PART_NUMBER CS24701JE04
J 0
(-2625 2725);
DISPLAY 0.978723 (-2625 2725);
DISPLAY INVISIBLE (-2625 2725);
FORCEADD Q_RES..1
(-2400 2575);
FORCEPROP 1 LAST LOCATION R1390
J 0
(-2750 2575);
DISPLAY 0.787234 (-2750 2575);
FORCEPROP 0 LAST $SEC 1
J 0
(-1950 2625);
DISPLAY 0.680851 (-1950 2625);
PAINT MONO (-1950 2625);
DISPLAY INVISIBLE (-1950 2625);
FORCEPROP 0 LAST CDS_SEC 1
J 0
(-1950 2625);
DISPLAY 0.680851 (-1950 2625);
DISPLAY INVISIBLE (-1950 2625);
FORCEPROP 1 LASTPIN (-2500 2575) $PN 1
J 0
(-2488 2587);
DISPLAY 0.787234 (-2488 2587);
PAINT MONO (-2488 2587);
FORCEPROP 1 LASTPIN (-2300 2575) $PN 2
J 0
(-2338 2587);
DISPLAY 0.787234 (-2338 2587);
PAINT MONO (-2338 2587);
FORCEPROP 1 LAST PACK_TYPE 0201LF
J 0
(-1950 2575);
DISPLAY 0.638298 (-1950 2575);
FORCEPROP 1 LAST VALUE 4.7K
J 2
(-2125 2575);
DISPLAY 0.638298 (-2125 2575);
FORCEPROP 1 LAST MATERIAL CHIP
J 0
(-2100 2575);
DISPLAY 0.638298 (-2100 2575);
FORCEPROP 1 LAST WATTAGE 1/20W
J 2
(-2125 2750);
DISPLAY 0.978723 (-2125 2750);
DISPLAY INVISIBLE (-2125 2750);
FORCEPROP 1 LAST TOLERANCE 5%
J 0
(-2600 2750);
DISPLAY 0.978723 (-2600 2750);
DISPLAY INVISIBLE (-2600 2750);
FORCEPROP 2 LAST CDS_LIB pure_quanta
J 0
(-2400 2575);
DISPLAY INVISIBLE (-2400 2575);
FORCEPROP 1 LAST PATH I105
J 0
(-2450 2725);
DISPLAY 0.978723 (-2450 2725);
PAINT WHITE (-2450 2725);
DISPLAY INVISIBLE (-2450 2725);
FORCEPROP 1 LAST PART_NUMBER CS24701JE04
J 0
(-2625 2675);
DISPLAY 0.978723 (-2625 2675);
DISPLAY INVISIBLE (-2625 2675);
FORCEADD Q_RES..1
(-2400 2525);
FORCEPROP 1 LAST LOCATION R1393
J 0
(-2750 2525);
DISPLAY 0.787234 (-2750 2525);
FORCEPROP 0 LAST $SEC 1
J 0
(-1950 2575);
DISPLAY 0.680851 (-1950 2575);
PAINT MONO (-1950 2575);
DISPLAY INVISIBLE (-1950 2575);
FORCEPROP 0 LAST CDS_SEC 1
J 0
(-1950 2575);
DISPLAY 0.680851 (-1950 2575);
DISPLAY INVISIBLE (-1950 2575);
FORCEPROP 1 LASTPIN (-2500 2525) $PN 1
J 0
(-2488 2537);
DISPLAY 0.787234 (-2488 2537);
PAINT MONO (-2488 2537);
FORCEPROP 1 LASTPIN (-2300 2525) $PN 2
J 0
(-2338 2537);
DISPLAY 0.787234 (-2338 2537);
PAINT MONO (-2338 2537);
FORCEPROP 1 LAST PACK_TYPE 0201LF
J 0
(-1950 2525);
DISPLAY 0.638298 (-1950 2525);
FORCEPROP 1 LAST MATERIAL CHIP
J 0
(-2100 2525);
DISPLAY 0.638298 (-2100 2525);
FORCEPROP 1 LAST VALUE 4.7K
J 2
(-2125 2525);
DISPLAY 0.638298 (-2125 2525);
FORCEPROP 1 LAST TOLERANCE 5%
J 0
(-2600 2700);
DISPLAY 0.978723 (-2600 2700);
DISPLAY INVISIBLE (-2600 2700);
FORCEPROP 1 LAST WATTAGE 1/20W
J 2
(-2125 2700);
DISPLAY 0.978723 (-2125 2700);
DISPLAY INVISIBLE (-2125 2700);
FORCEPROP 2 LAST CDS_LIB pure_quanta
J 0
(-2400 2525);
DISPLAY INVISIBLE (-2400 2525);
FORCEPROP 1 LAST PATH I106
J 0
(-2450 2675);
DISPLAY 0.978723 (-2450 2675);
PAINT WHITE (-2450 2675);
DISPLAY INVISIBLE (-2450 2675);
FORCEPROP 1 LAST PART_NUMBER CS24701JE04
J 0
(-2625 2625);
DISPLAY 0.978723 (-2625 2625);
DISPLAY INVISIBLE (-2625 2625);
FORCEADD Q_RES..1
(-2400 2475);
FORCEPROP 1 LAST LOCATION R1394
J 0
(-2750 2475);
DISPLAY 0.787234 (-2750 2475);
FORCEPROP 0 LAST $SEC 1
J 0
(-1950 2525);
DISPLAY 0.680851 (-1950 2525);
PAINT MONO (-1950 2525);
DISPLAY INVISIBLE (-1950 2525);
FORCEPROP 0 LAST CDS_SEC 1
J 0
(-1950 2525);
DISPLAY 0.680851 (-1950 2525);
DISPLAY INVISIBLE (-1950 2525);
FORCEPROP 1 LASTPIN (-2500 2475) $PN 1
J 0
(-2488 2487);
DISPLAY 0.787234 (-2488 2487);
PAINT MONO (-2488 2487);
FORCEPROP 1 LASTPIN (-2300 2475) $PN 2
J 0
(-2338 2487);
DISPLAY 0.787234 (-2338 2487);
PAINT MONO (-2338 2487);
FORCEPROP 1 LAST PACK_TYPE 0201LF
J 0
(-1950 2475);
DISPLAY 0.638298 (-1950 2475);
FORCEPROP 1 LAST MATERIAL CHIP
J 0
(-2100 2475);
DISPLAY 0.638298 (-2100 2475);
FORCEPROP 1 LAST VALUE 4.7K
J 2
(-2125 2475);
DISPLAY 0.638298 (-2125 2475);
FORCEPROP 1 LAST TOLERANCE 5%
J 0
(-2600 2650);
DISPLAY 0.978723 (-2600 2650);
DISPLAY INVISIBLE (-2600 2650);
FORCEPROP 1 LAST WATTAGE 1/20W
J 2
(-2125 2650);
DISPLAY 0.978723 (-2125 2650);
DISPLAY INVISIBLE (-2125 2650);
FORCEPROP 2 LAST CDS_LIB pure_quanta
J 0
(-2400 2475);
DISPLAY INVISIBLE (-2400 2475);
FORCEPROP 1 LAST PATH I107
J 0
(-2450 2625);
DISPLAY 0.978723 (-2450 2625);
PAINT WHITE (-2450 2625);
DISPLAY INVISIBLE (-2450 2625);
FORCEPROP 1 LAST PART_NUMBER CS24701JE04
J 0
(-2625 2575);
DISPLAY 0.978723 (-2625 2575);
DISPLAY INVISIBLE (-2625 2575);
FORCEADD Q_RES..1
(-2400 2425);
FORCEPROP 1 LAST LOCATION R1399
J 0
(-2750 2425);
DISPLAY 0.787234 (-2750 2425);
FORCEPROP 0 LAST $SEC 1
J 0
(-1950 2475);
DISPLAY 0.680851 (-1950 2475);
PAINT MONO (-1950 2475);
DISPLAY INVISIBLE (-1950 2475);
FORCEPROP 0 LAST CDS_SEC 1
J 0
(-1950 2475);
DISPLAY 0.680851 (-1950 2475);
DISPLAY INVISIBLE (-1950 2475);
FORCEPROP 1 LASTPIN (-2500 2425) $PN 1
J 0
(-2488 2437);
DISPLAY 0.787234 (-2488 2437);
PAINT MONO (-2488 2437);
FORCEPROP 1 LASTPIN (-2300 2425) $PN 2
J 0
(-2338 2437);
DISPLAY 0.787234 (-2338 2437);
PAINT MONO (-2338 2437);
FORCEPROP 1 LAST PACK_TYPE 0201LF
J 0
(-1950 2425);
DISPLAY 0.638298 (-1950 2425);
FORCEPROP 1 LAST MATERIAL CHIP
J 0
(-2100 2425);
DISPLAY 0.638298 (-2100 2425);
FORCEPROP 1 LAST VALUE 4.7K
J 2
(-2125 2425);
DISPLAY 0.638298 (-2125 2425);
FORCEPROP 1 LAST TOLERANCE 5%
J 0
(-2600 2600);
DISPLAY 0.978723 (-2600 2600);
DISPLAY INVISIBLE (-2600 2600);
FORCEPROP 1 LAST WATTAGE 1/20W
J 2
(-2125 2600);
DISPLAY 0.978723 (-2125 2600);
DISPLAY INVISIBLE (-2125 2600);
FORCEPROP 2 LAST CDS_LIB pure_quanta
J 0
(-2400 2425);
DISPLAY INVISIBLE (-2400 2425);
FORCEPROP 1 LAST PATH I108
J 0
(-2450 2575);
DISPLAY 0.978723 (-2450 2575);
PAINT WHITE (-2450 2575);
DISPLAY INVISIBLE (-2450 2575);
FORCEPROP 1 LAST PART_NUMBER CS24701JE04
J 0
(-2625 2525);
DISPLAY 0.978723 (-2625 2525);
DISPLAY INVISIBLE (-2625 2525);
FORCEADD Q_RES..1
(-2400 2375);
FORCEPROP 1 LAST LOCATION R1402
J 0
(-2750 2375);
DISPLAY 0.787234 (-2750 2375);
FORCEPROP 0 LAST $SEC 1
J 0
(-1950 2425);
DISPLAY 0.680851 (-1950 2425);
PAINT MONO (-1950 2425);
DISPLAY INVISIBLE (-1950 2425);
FORCEPROP 0 LAST CDS_SEC 1
J 0
(-1950 2425);
DISPLAY 0.680851 (-1950 2425);
DISPLAY INVISIBLE (-1950 2425);
FORCEPROP 1 LASTPIN (-2500 2375) $PN 1
J 0
(-2488 2387);
DISPLAY 0.787234 (-2488 2387);
PAINT MONO (-2488 2387);
FORCEPROP 1 LASTPIN (-2300 2375) $PN 2
J 0
(-2338 2387);
DISPLAY 0.787234 (-2338 2387);
PAINT MONO (-2338 2387);
FORCEPROP 1 LAST PACK_TYPE 0201LF
J 0
(-1950 2375);
DISPLAY 0.638298 (-1950 2375);
FORCEPROP 1 LAST MATERIAL CHIP
J 0
(-2100 2375);
DISPLAY 0.638298 (-2100 2375);
FORCEPROP 1 LAST VALUE 4.7K
J 2
(-2125 2375);
DISPLAY 0.638298 (-2125 2375);
FORCEPROP 1 LAST WATTAGE 1/20W
J 2
(-2125 2550);
DISPLAY 0.978723 (-2125 2550);
DISPLAY INVISIBLE (-2125 2550);
FORCEPROP 1 LAST TOLERANCE 5%
J 0
(-2600 2550);
DISPLAY 0.978723 (-2600 2550);
DISPLAY INVISIBLE (-2600 2550);
FORCEPROP 2 LAST CDS_LIB pure_quanta
J 0
(-2400 2375);
DISPLAY INVISIBLE (-2400 2375);
FORCEPROP 1 LAST PATH I109
J 0
(-2450 2525);
DISPLAY 0.978723 (-2450 2525);
PAINT WHITE (-2450 2525);
DISPLAY INVISIBLE (-2450 2525);
FORCEPROP 1 LAST PART_NUMBER CS24701JE04
J 0
(-2625 2475);
DISPLAY 0.978723 (-2625 2475);
DISPLAY INVISIBLE (-2625 2475);
FORCEADD OFFPAGE..5
R 2
(-6975 1650);
FORCEPROP 2 LAST $XR0 185 
J 0
(-6786 1650);
DISPLAY 0.638298 (-6786 1650);
PAINT MONO (-6786 1650);
FORCEPROP 2 LAST CDS_LIB standard
J 0
(-6975 1650);
DISPLAY INVISIBLE (-6975 1650);
FORCEPROP 1 LAST OFFPAGE TRUE
J 2
(-7300 1525);
DISPLAY 0.872340 (-7300 1525);
PAINT GREEN (-7300 1525);
DISPLAY INVISIBLE (-7300 1525);
FORCEPROP 1 LAST COMMENT_BODY TRUE
J 2
(-7075 1575);
DISPLAY 0.872340 (-7075 1575);
PAINT GREEN (-7075 1575);
DISPLAY INVISIBLE (-7075 1575);
FORCEPROP 2 LAST PATH I11
J 0
(-6775 1700);
DISPLAY 0.680851 (-6775 1700);
DISPLAY INVISIBLE (-6775 1700);
FORCEADD Q_RES..1
(-2400 2325);
FORCEPROP 1 LAST LOCATION R1403
J 0
(-2750 2325);
DISPLAY 0.787234 (-2750 2325);
FORCEPROP 0 LAST $SEC 1
J 0
(-1950 2375);
DISPLAY 0.680851 (-1950 2375);
PAINT MONO (-1950 2375);
DISPLAY INVISIBLE (-1950 2375);
FORCEPROP 0 LAST CDS_SEC 1
J 0
(-1950 2375);
DISPLAY 0.680851 (-1950 2375);
DISPLAY INVISIBLE (-1950 2375);
FORCEPROP 1 LASTPIN (-2500 2325) $PN 1
J 0
(-2488 2337);
DISPLAY 0.787234 (-2488 2337);
PAINT MONO (-2488 2337);
FORCEPROP 1 LASTPIN (-2300 2325) $PN 2
J 0
(-2338 2337);
DISPLAY 0.787234 (-2338 2337);
PAINT MONO (-2338 2337);
FORCEPROP 1 LAST PACK_TYPE 0201LF
J 0
(-1950 2325);
DISPLAY 0.638298 (-1950 2325);
FORCEPROP 1 LAST MATERIAL CHIP
J 0
(-2100 2325);
DISPLAY 0.638298 (-2100 2325);
FORCEPROP 1 LAST VALUE 4.7K
J 2
(-2125 2325);
DISPLAY 0.638298 (-2125 2325);
FORCEPROP 1 LAST TOLERANCE 5%
J 0
(-2600 2500);
DISPLAY 0.978723 (-2600 2500);
DISPLAY INVISIBLE (-2600 2500);
FORCEPROP 1 LAST WATTAGE 1/20W
J 2
(-2125 2500);
DISPLAY 0.978723 (-2125 2500);
DISPLAY INVISIBLE (-2125 2500);
FORCEPROP 2 LAST CDS_LIB pure_quanta
J 0
(-2400 2325);
DISPLAY INVISIBLE (-2400 2325);
FORCEPROP 1 LAST PATH I110
J 0
(-2450 2475);
DISPLAY 0.978723 (-2450 2475);
PAINT WHITE (-2450 2475);
DISPLAY INVISIBLE (-2450 2475);
FORCEPROP 1 LAST PART_NUMBER CS24701JE04
J 0
(-2625 2425);
DISPLAY 0.978723 (-2625 2425);
DISPLAY INVISIBLE (-2625 2425);
FORCEADD Q_RES..1
(-2400 2275);
FORCEPROP 1 LAST LOCATION R1407
J 0
(-2750 2275);
DISPLAY 0.787234 (-2750 2275);
FORCEPROP 0 LAST $SEC 1
J 0
(-1950 2325);
DISPLAY 0.680851 (-1950 2325);
PAINT MONO (-1950 2325);
DISPLAY INVISIBLE (-1950 2325);
FORCEPROP 0 LAST CDS_SEC 1
J 0
(-1950 2325);
DISPLAY 0.680851 (-1950 2325);
DISPLAY INVISIBLE (-1950 2325);
FORCEPROP 1 LASTPIN (-2500 2275) $PN 1
J 0
(-2488 2287);
DISPLAY 0.787234 (-2488 2287);
PAINT MONO (-2488 2287);
FORCEPROP 1 LASTPIN (-2300 2275) $PN 2
J 0
(-2338 2287);
DISPLAY 0.787234 (-2338 2287);
PAINT MONO (-2338 2287);
FORCEPROP 1 LAST VALUE 4.7K
J 2
(-2125 2275);
DISPLAY 0.638298 (-2125 2275);
FORCEPROP 1 LAST PACK_TYPE 0201LF
J 0
(-1950 2275);
DISPLAY 0.638298 (-1950 2275);
FORCEPROP 1 LAST MATERIAL CHIP
J 0
(-2100 2275);
DISPLAY 0.638298 (-2100 2275);
FORCEPROP 1 LAST TOLERANCE 5%
J 0
(-2600 2450);
DISPLAY 0.978723 (-2600 2450);
DISPLAY INVISIBLE (-2600 2450);
FORCEPROP 1 LAST WATTAGE 1/20W
J 2
(-2125 2450);
DISPLAY 0.978723 (-2125 2450);
DISPLAY INVISIBLE (-2125 2450);
FORCEPROP 2 LAST CDS_LIB pure_quanta
J 0
(-2400 2275);
DISPLAY INVISIBLE (-2400 2275);
FORCEPROP 1 LAST PATH I111
J 0
(-2450 2425);
DISPLAY 0.978723 (-2450 2425);
PAINT WHITE (-2450 2425);
DISPLAY INVISIBLE (-2450 2425);
FORCEPROP 1 LAST PART_NUMBER CS24701JE04
J 0
(-2625 2375);
DISPLAY 0.978723 (-2625 2375);
DISPLAY INVISIBLE (-2625 2375);
FORCEADD P1V0..1
(-3025 2975);
FORCEPROP 3 LASTPIN (-3025 2925) SIG_NAME P1V8_CPU1_RT_1D\g
J 0
(-3015 2935);
DISPLAY 0.659574 (-3015 2935);
PAINT MONO (-3015 2935);
DISPLAY INVISIBLE (-3015 2935);
FORCEPROP 1 LAST HDL_POWER P1V8_CPU1_RT_1D
J 1
(-3025 3025);
DISPLAY 0.957447 (-3025 3025);
PAINT SKYBLUE (-3025 3025);
FORCEPROP 2 LAST CDS_LIB pure_quanta_power
J 0
(-3025 2975);
DISPLAY INVISIBLE (-3025 2975);
FORCEPROP 1 LAST PATH I112
J 0
(-2975 3000);
DISPLAY 0.872340 (-2975 3000);
PAINT AQUA (-2975 3000);
DISPLAY INVISIBLE (-2975 3000);
FORCEADD OFFPAGE..2
(-3950 2650);
FORCEPROP 2 LAST $XR0 185 
J 0
(-3761 2650);
DISPLAY 0.638298 (-3761 2650);
PAINT MONO (-3761 2650);
FORCEPROP 2 LAST CDS_LIB standard
J 0
(-3950 2650);
DISPLAY INVISIBLE (-3950 2650);
FORCEPROP 1 LAST OFFPAGE TRUE
J 0
(-3625 2525);
DISPLAY 0.872340 (-3625 2525);
PAINT GREEN (-3625 2525);
DISPLAY INVISIBLE (-3625 2525);
FORCEPROP 1 LAST COMMENT_BODY TRUE
J 0
(-3995 2555);
DISPLAY 0.872340 (-3995 2555);
PAINT GREEN (-3995 2555);
DISPLAY INVISIBLE (-3995 2555);
FORCEPROP 2 LAST PATH I113
J 0
(-3775 2725);
DISPLAY 0.680851 (-3775 2725);
DISPLAY INVISIBLE (-3775 2725);
FORCEADD OFFPAGE..2
(-3950 2600);
FORCEPROP 2 LAST $XR0 185 
J 0
(-3761 2600);
DISPLAY 0.638298 (-3761 2600);
PAINT MONO (-3761 2600);
FORCEPROP 2 LAST CDS_LIB standard
J 0
(-3950 2600);
DISPLAY INVISIBLE (-3950 2600);
FORCEPROP 1 LAST OFFPAGE TRUE
J 0
(-3625 2475);
DISPLAY 0.872340 (-3625 2475);
PAINT GREEN (-3625 2475);
DISPLAY INVISIBLE (-3625 2475);
FORCEPROP 1 LAST COMMENT_BODY TRUE
J 0
(-3995 2505);
DISPLAY 0.872340 (-3995 2505);
PAINT GREEN (-3995 2505);
DISPLAY INVISIBLE (-3995 2505);
FORCEPROP 2 LAST PATH I114
J 0
(-3775 2675);
DISPLAY 0.680851 (-3775 2675);
DISPLAY INVISIBLE (-3775 2675);
FORCEADD OFFPAGE..2
(-3950 2550);
FORCEPROP 2 LAST $XR0 185 
J 0
(-3761 2550);
DISPLAY 0.638298 (-3761 2550);
PAINT MONO (-3761 2550);
FORCEPROP 2 LAST CDS_LIB standard
J 0
(-3950 2550);
DISPLAY INVISIBLE (-3950 2550);
FORCEPROP 1 LAST OFFPAGE TRUE
J 0
(-3625 2425);
DISPLAY 0.872340 (-3625 2425);
PAINT GREEN (-3625 2425);
DISPLAY INVISIBLE (-3625 2425);
FORCEPROP 1 LAST COMMENT_BODY TRUE
J 0
(-3995 2455);
DISPLAY 0.872340 (-3995 2455);
PAINT GREEN (-3995 2455);
DISPLAY INVISIBLE (-3995 2455);
FORCEPROP 2 LAST PATH I115
J 0
(-3775 2625);
DISPLAY 0.680851 (-3775 2625);
DISPLAY INVISIBLE (-3775 2625);
FORCEADD OFFPAGE..2
(-3950 2500);
FORCEPROP 2 LAST $XR0 185 
J 0
(-3761 2500);
DISPLAY 0.638298 (-3761 2500);
PAINT MONO (-3761 2500);
FORCEPROP 2 LAST CDS_LIB standard
J 0
(-3950 2500);
DISPLAY INVISIBLE (-3950 2500);
FORCEPROP 1 LAST OFFPAGE TRUE
J 0
(-3625 2375);
DISPLAY 0.872340 (-3625 2375);
PAINT GREEN (-3625 2375);
DISPLAY INVISIBLE (-3625 2375);
FORCEPROP 1 LAST COMMENT_BODY TRUE
J 0
(-3995 2405);
DISPLAY 0.872340 (-3995 2405);
PAINT GREEN (-3995 2405);
DISPLAY INVISIBLE (-3995 2405);
FORCEPROP 2 LAST PATH I116
J 0
(-3775 2575);
DISPLAY 0.680851 (-3775 2575);
DISPLAY INVISIBLE (-3775 2575);
FORCEADD OFFPAGE..2
(-3950 2450);
FORCEPROP 2 LAST $XR0 185 
J 0
(-3761 2450);
DISPLAY 0.638298 (-3761 2450);
PAINT MONO (-3761 2450);
FORCEPROP 2 LAST CDS_LIB standard
J 0
(-3950 2450);
DISPLAY INVISIBLE (-3950 2450);
FORCEPROP 1 LAST OFFPAGE TRUE
J 0
(-3625 2325);
DISPLAY 0.872340 (-3625 2325);
PAINT GREEN (-3625 2325);
DISPLAY INVISIBLE (-3625 2325);
FORCEPROP 1 LAST COMMENT_BODY TRUE
J 0
(-3995 2355);
DISPLAY 0.872340 (-3995 2355);
PAINT GREEN (-3995 2355);
DISPLAY INVISIBLE (-3995 2355);
FORCEPROP 2 LAST PATH I117
J 0
(-3775 2525);
DISPLAY 0.680851 (-3775 2525);
DISPLAY INVISIBLE (-3775 2525);
FORCEADD OFFPAGE..2
(-3950 2400);
FORCEPROP 2 LAST $XR0 185 
J 0
(-3761 2400);
DISPLAY 0.638298 (-3761 2400);
PAINT MONO (-3761 2400);
FORCEPROP 2 LAST CDS_LIB standard
J 0
(-3950 2400);
DISPLAY INVISIBLE (-3950 2400);
FORCEPROP 1 LAST OFFPAGE TRUE
J 0
(-3625 2275);
DISPLAY 0.872340 (-3625 2275);
PAINT GREEN (-3625 2275);
DISPLAY INVISIBLE (-3625 2275);
FORCEPROP 1 LAST COMMENT_BODY TRUE
J 0
(-3995 2305);
DISPLAY 0.872340 (-3995 2305);
PAINT GREEN (-3995 2305);
DISPLAY INVISIBLE (-3995 2305);
FORCEPROP 2 LAST PATH I118
J 0
(-3775 2475);
DISPLAY 0.680851 (-3775 2475);
DISPLAY INVISIBLE (-3775 2475);
FORCEADD OFFPAGE..2
(-3950 2350);
FORCEPROP 2 LAST $XR0 185 
J 0
(-3761 2350);
DISPLAY 0.638298 (-3761 2350);
PAINT MONO (-3761 2350);
FORCEPROP 2 LAST CDS_LIB standard
J 0
(-3950 2350);
DISPLAY INVISIBLE (-3950 2350);
FORCEPROP 1 LAST OFFPAGE TRUE
J 0
(-3625 2225);
DISPLAY 0.872340 (-3625 2225);
PAINT GREEN (-3625 2225);
DISPLAY INVISIBLE (-3625 2225);
FORCEPROP 1 LAST COMMENT_BODY TRUE
J 0
(-3995 2255);
DISPLAY 0.872340 (-3995 2255);
PAINT GREEN (-3995 2255);
DISPLAY INVISIBLE (-3995 2255);
FORCEPROP 2 LAST PATH I119
J 0
(-3775 2425);
DISPLAY 0.680851 (-3775 2425);
DISPLAY INVISIBLE (-3775 2425);
FORCEADD OFFPAGE..5
R 2
(-6975 1750);
FORCEPROP 2 LAST $XR0 185 
J 0
(-6786 1750);
DISPLAY 0.638298 (-6786 1750);
PAINT MONO (-6786 1750);
FORCEPROP 2 LAST CDS_LIB standard
J 0
(-6975 1750);
DISPLAY INVISIBLE (-6975 1750);
FORCEPROP 1 LAST OFFPAGE TRUE
J 2
(-7300 1625);
DISPLAY 0.872340 (-7300 1625);
PAINT GREEN (-7300 1625);
DISPLAY INVISIBLE (-7300 1625);
FORCEPROP 1 LAST COMMENT_BODY TRUE
J 2
(-7075 1675);
DISPLAY 0.872340 (-7075 1675);
PAINT GREEN (-7075 1675);
DISPLAY INVISIBLE (-7075 1675);
FORCEPROP 2 LAST PATH I12
J 0
(-6775 1800);
DISPLAY 0.680851 (-6775 1800);
DISPLAY INVISIBLE (-6775 1800);
FORCEADD OFFPAGE..2
(-3950 2300);
FORCEPROP 2 LAST $XR0 185 
J 0
(-3761 2300);
DISPLAY 0.638298 (-3761 2300);
PAINT MONO (-3761 2300);
FORCEPROP 2 LAST CDS_LIB standard
J 0
(-3950 2300);
DISPLAY INVISIBLE (-3950 2300);
FORCEPROP 1 LAST OFFPAGE TRUE
J 0
(-3625 2175);
DISPLAY 0.872340 (-3625 2175);
PAINT GREEN (-3625 2175);
DISPLAY INVISIBLE (-3625 2175);
FORCEPROP 1 LAST COMMENT_BODY TRUE
J 0
(-3995 2205);
DISPLAY 0.872340 (-3995 2205);
PAINT GREEN (-3995 2205);
DISPLAY INVISIBLE (-3995 2205);
FORCEPROP 2 LAST PATH I120
J 0
(-3775 2375);
DISPLAY 0.680851 (-3775 2375);
DISPLAY INVISIBLE (-3775 2375);
FORCEADD Q_RES..1
(-5550 2600);
FORCEPROP 1 LAST LOCATION R1367
J 0
(-5825 2600);
DISPLAY 0.787234 (-5825 2600);
FORCEPROP 0 LAST $SEC 1
J 0
(-5100 2650);
DISPLAY 0.680851 (-5100 2650);
PAINT MONO (-5100 2650);
DISPLAY INVISIBLE (-5100 2650);
FORCEPROP 0 LAST CDS_SEC 1
J 0
(-5100 2650);
DISPLAY 0.680851 (-5100 2650);
DISPLAY INVISIBLE (-5100 2650);
FORCEPROP 1 LASTPIN (-5650 2600) $PN 1
J 0
(-5638 2612);
DISPLAY 0.787234 (-5638 2612);
PAINT MONO (-5638 2612);
FORCEPROP 1 LASTPIN (-5450 2600) $PN 2
J 0
(-5488 2612);
DISPLAY 0.787234 (-5488 2612);
PAINT MONO (-5488 2612);
FORCEPROP 1 LAST VALUE 4.7K
J 2
(-5275 2600);
DISPLAY 0.638298 (-5275 2600);
FORCEPROP 1 LAST MATERIAL CHIP
J 0
(-5250 2600);
DISPLAY 0.638298 (-5250 2600);
FORCEPROP 1 LAST PACK_TYPE 0201LF
J 0
(-5100 2600);
DISPLAY 0.638298 (-5100 2600);
FORCEPROP 1 LAST TOLERANCE 5%
J 0
(-5750 2775);
DISPLAY 0.978723 (-5750 2775);
DISPLAY INVISIBLE (-5750 2775);
FORCEPROP 1 LAST WATTAGE 1/20W
J 2
(-5275 2775);
DISPLAY 0.978723 (-5275 2775);
DISPLAY INVISIBLE (-5275 2775);
FORCEPROP 2 LAST CDS_LIB pure_quanta
J 0
(-5550 2600);
DISPLAY INVISIBLE (-5550 2600);
FORCEPROP 1 LAST PATH I121
J 0
(-5600 2750);
DISPLAY 0.978723 (-5600 2750);
PAINT WHITE (-5600 2750);
DISPLAY INVISIBLE (-5600 2750);
FORCEPROP 1 LAST PART_NUMBER CS24701JE04
J 0
(-5775 2700);
DISPLAY 0.978723 (-5775 2700);
DISPLAY INVISIBLE (-5775 2700);
FORCEADD Q_RES..1
(-5550 2650);
FORCEPROP 1 LAST LOCATION R1366
J 0
(-5825 2650);
DISPLAY 0.787234 (-5825 2650);
FORCEPROP 0 LAST $SEC 1
J 0
(-5350 2825);
DISPLAY 0.680851 (-5350 2825);
PAINT MONO (-5350 2825);
DISPLAY INVISIBLE (-5350 2825);
FORCEPROP 0 LAST CDS_SEC 1
J 0
(-5350 2825);
DISPLAY 0.680851 (-5350 2825);
DISPLAY INVISIBLE (-5350 2825);
FORCEPROP 1 LASTPIN (-5650 2650) $PN 1
J 0
(-5638 2662);
DISPLAY 0.787234 (-5638 2662);
PAINT MONO (-5638 2662);
FORCEPROP 1 LASTPIN (-5450 2650) $PN 2
J 0
(-5488 2662);
DISPLAY 0.787234 (-5488 2662);
PAINT MONO (-5488 2662);
FORCEPROP 1 LAST TOLERANCE 5%
J 0
(-5750 2775);
DISPLAY 0.787234 (-5750 2775);
FORCEPROP 1 LAST PACK_TYPE 0201LF
J 0
(-5100 2650);
DISPLAY 0.638298 (-5100 2650);
FORCEPROP 1 LAST MATERIAL CHIP
J 0
(-5250 2650);
DISPLAY 0.638298 (-5250 2650);
FORCEPROP 1 LAST WATTAGE 1/20W
J 2
(-5350 2775);
DISPLAY 0.787234 (-5350 2775);
FORCEPROP 1 LAST VALUE 4.7K
J 2
(-5275 2650);
DISPLAY 0.638298 (-5275 2650);
FORCEPROP 2 LAST CDS_LIB pure_quanta
J 0
(-5550 2650);
DISPLAY INVISIBLE (-5550 2650);
FORCEPROP 1 LAST PATH I122
J 0
(-5600 2800);
DISPLAY 0.978723 (-5600 2800);
PAINT WHITE (-5600 2800);
DISPLAY INVISIBLE (-5600 2800);
FORCEPROP 1 LAST PART_NUMBER CS24701JE04
J 0
(-5750 2725);
DISPLAY 0.787234 (-5750 2725);
DISPLAY INVISIBLE (-5750 2725);
FORCEADD Q_RES..1
(-5550 2500);
FORCEPROP 1 LAST LOCATION R1374
J 0
(-5825 2500);
DISPLAY 0.787234 (-5825 2500);
FORCEPROP 0 LAST $SEC 1
J 0
(-5100 2550);
DISPLAY 0.680851 (-5100 2550);
PAINT MONO (-5100 2550);
DISPLAY INVISIBLE (-5100 2550);
FORCEPROP 0 LAST CDS_SEC 1
J 0
(-5100 2550);
DISPLAY 0.680851 (-5100 2550);
DISPLAY INVISIBLE (-5100 2550);
FORCEPROP 1 LASTPIN (-5650 2500) $PN 1
J 0
(-5638 2512);
DISPLAY 0.787234 (-5638 2512);
PAINT MONO (-5638 2512);
FORCEPROP 1 LASTPIN (-5450 2500) $PN 2
J 0
(-5488 2512);
DISPLAY 0.787234 (-5488 2512);
PAINT MONO (-5488 2512);
FORCEPROP 1 LAST MATERIAL CHIP
J 0
(-5250 2500);
DISPLAY 0.638298 (-5250 2500);
FORCEPROP 1 LAST VALUE 4.7K
J 2
(-5275 2500);
DISPLAY 0.638298 (-5275 2500);
FORCEPROP 1 LAST PACK_TYPE 0201LF
J 0
(-5100 2500);
DISPLAY 0.638298 (-5100 2500);
FORCEPROP 1 LAST WATTAGE 1/20W
J 2
(-5275 2675);
DISPLAY 0.978723 (-5275 2675);
DISPLAY INVISIBLE (-5275 2675);
FORCEPROP 1 LAST TOLERANCE 5%
J 0
(-5750 2675);
DISPLAY 0.978723 (-5750 2675);
DISPLAY INVISIBLE (-5750 2675);
FORCEPROP 2 LAST CDS_LIB pure_quanta
J 0
(-5550 2500);
DISPLAY INVISIBLE (-5550 2500);
FORCEPROP 1 LAST PATH I123
J 0
(-5600 2650);
DISPLAY 0.978723 (-5600 2650);
PAINT WHITE (-5600 2650);
DISPLAY INVISIBLE (-5600 2650);
FORCEPROP 1 LAST PART_NUMBER CS24701JE04
J 0
(-5775 2600);
DISPLAY 0.978723 (-5775 2600);
DISPLAY INVISIBLE (-5775 2600);
FORCEADD Q_RES..1
(-5550 2550);
FORCEPROP 1 LAST LOCATION R1371
J 0
(-5825 2550);
DISPLAY 0.787234 (-5825 2550);
FORCEPROP 0 LAST $SEC 1
J 0
(-5100 2600);
DISPLAY 0.680851 (-5100 2600);
PAINT MONO (-5100 2600);
DISPLAY INVISIBLE (-5100 2600);
FORCEPROP 0 LAST CDS_SEC 1
J 0
(-5100 2600);
DISPLAY 0.680851 (-5100 2600);
DISPLAY INVISIBLE (-5100 2600);
FORCEPROP 1 LASTPIN (-5650 2550) $PN 1
J 0
(-5638 2562);
DISPLAY 0.787234 (-5638 2562);
PAINT MONO (-5638 2562);
FORCEPROP 1 LASTPIN (-5450 2550) $PN 2
J 0
(-5488 2562);
DISPLAY 0.787234 (-5488 2562);
PAINT MONO (-5488 2562);
FORCEPROP 1 LAST VALUE 4.7K
J 2
(-5275 2550);
DISPLAY 0.638298 (-5275 2550);
FORCEPROP 1 LAST PACK_TYPE 0201LF
J 0
(-5100 2550);
DISPLAY 0.638298 (-5100 2550);
FORCEPROP 1 LAST MATERIAL CHIP
J 0
(-5250 2550);
DISPLAY 0.638298 (-5250 2550);
FORCEPROP 1 LAST WATTAGE 1/20W
J 2
(-5275 2725);
DISPLAY 0.978723 (-5275 2725);
DISPLAY INVISIBLE (-5275 2725);
FORCEPROP 1 LAST TOLERANCE 5%
J 0
(-5750 2725);
DISPLAY 0.978723 (-5750 2725);
DISPLAY INVISIBLE (-5750 2725);
FORCEPROP 2 LAST CDS_LIB pure_quanta
J 0
(-5550 2550);
DISPLAY INVISIBLE (-5550 2550);
FORCEPROP 1 LAST PATH I124
J 0
(-5600 2700);
DISPLAY 0.978723 (-5600 2700);
PAINT WHITE (-5600 2700);
DISPLAY INVISIBLE (-5600 2700);
FORCEPROP 1 LAST PART_NUMBER CS24701JE04
J 0
(-5775 2650);
DISPLAY 0.978723 (-5775 2650);
DISPLAY INVISIBLE (-5775 2650);
FORCEADD Q_RES..1
(-5550 2450);
FORCEPROP 1 LAST LOCATION R1375
J 0
(-5825 2450);
DISPLAY 0.787234 (-5825 2450);
FORCEPROP 0 LAST $SEC 1
J 0
(-5100 2500);
DISPLAY 0.680851 (-5100 2500);
PAINT MONO (-5100 2500);
DISPLAY INVISIBLE (-5100 2500);
FORCEPROP 0 LAST CDS_SEC 1
J 0
(-5100 2500);
DISPLAY 0.680851 (-5100 2500);
DISPLAY INVISIBLE (-5100 2500);
FORCEPROP 1 LASTPIN (-5650 2450) $PN 1
J 0
(-5638 2462);
DISPLAY 0.787234 (-5638 2462);
PAINT MONO (-5638 2462);
FORCEPROP 1 LASTPIN (-5450 2450) $PN 2
J 0
(-5488 2462);
DISPLAY 0.787234 (-5488 2462);
PAINT MONO (-5488 2462);
FORCEPROP 1 LAST VALUE 4.7K
J 2
(-5275 2450);
DISPLAY 0.638298 (-5275 2450);
FORCEPROP 1 LAST MATERIAL CHIP
J 0
(-5250 2450);
DISPLAY 0.638298 (-5250 2450);
FORCEPROP 1 LAST PACK_TYPE 0201LF
J 0
(-5100 2450);
DISPLAY 0.638298 (-5100 2450);
FORCEPROP 1 LAST WATTAGE 1/20W
J 2
(-5275 2625);
DISPLAY 0.978723 (-5275 2625);
DISPLAY INVISIBLE (-5275 2625);
FORCEPROP 1 LAST TOLERANCE 5%
J 0
(-5750 2625);
DISPLAY 0.978723 (-5750 2625);
DISPLAY INVISIBLE (-5750 2625);
FORCEPROP 2 LAST CDS_LIB pure_quanta
J 0
(-5550 2450);
DISPLAY INVISIBLE (-5550 2450);
FORCEPROP 1 LAST PATH I125
J 0
(-5600 2600);
DISPLAY 0.978723 (-5600 2600);
PAINT WHITE (-5600 2600);
DISPLAY INVISIBLE (-5600 2600);
FORCEPROP 1 LAST PART_NUMBER CS24701JE04
J 0
(-5775 2550);
DISPLAY 0.978723 (-5775 2550);
DISPLAY INVISIBLE (-5775 2550);
FORCEADD Q_RES..1
(-5550 2400);
FORCEPROP 1 LAST LOCATION R1379
J 0
(-5825 2400);
DISPLAY 0.787234 (-5825 2400);
FORCEPROP 0 LAST $SEC 1
J 0
(-5100 2450);
DISPLAY 0.680851 (-5100 2450);
PAINT MONO (-5100 2450);
DISPLAY INVISIBLE (-5100 2450);
FORCEPROP 0 LAST CDS_SEC 1
J 0
(-5100 2450);
DISPLAY 0.680851 (-5100 2450);
DISPLAY INVISIBLE (-5100 2450);
FORCEPROP 1 LASTPIN (-5650 2400) $PN 1
J 0
(-5638 2412);
DISPLAY 0.787234 (-5638 2412);
PAINT MONO (-5638 2412);
FORCEPROP 1 LASTPIN (-5450 2400) $PN 2
J 0
(-5488 2412);
DISPLAY 0.787234 (-5488 2412);
PAINT MONO (-5488 2412);
FORCEPROP 1 LAST PACK_TYPE 0201LF
J 0
(-5100 2400);
DISPLAY 0.638298 (-5100 2400);
FORCEPROP 1 LAST VALUE 4.7K
J 2
(-5275 2400);
DISPLAY 0.638298 (-5275 2400);
FORCEPROP 1 LAST MATERIAL CHIP
J 0
(-5250 2400);
DISPLAY 0.638298 (-5250 2400);
FORCEPROP 1 LAST TOLERANCE 5%
J 0
(-5750 2575);
DISPLAY 0.978723 (-5750 2575);
DISPLAY INVISIBLE (-5750 2575);
FORCEPROP 1 LAST WATTAGE 1/20W
J 2
(-5275 2575);
DISPLAY 0.978723 (-5275 2575);
DISPLAY INVISIBLE (-5275 2575);
FORCEPROP 2 LAST CDS_LIB pure_quanta
J 0
(-5550 2400);
DISPLAY INVISIBLE (-5550 2400);
FORCEPROP 1 LAST PATH I126
J 0
(-5600 2550);
DISPLAY 0.978723 (-5600 2550);
PAINT WHITE (-5600 2550);
DISPLAY INVISIBLE (-5600 2550);
FORCEPROP 1 LAST PART_NUMBER CS24701JE04
J 0
(-5775 2500);
DISPLAY 0.978723 (-5775 2500);
DISPLAY INVISIBLE (-5775 2500);
FORCEADD Q_RES..1
(-5550 2350);
FORCEPROP 1 LAST LOCATION R1382
J 0
(-5825 2350);
DISPLAY 0.787234 (-5825 2350);
FORCEPROP 0 LAST $SEC 1
J 0
(-5100 2400);
DISPLAY 0.680851 (-5100 2400);
PAINT MONO (-5100 2400);
DISPLAY INVISIBLE (-5100 2400);
FORCEPROP 0 LAST CDS_SEC 1
J 0
(-5100 2400);
DISPLAY 0.680851 (-5100 2400);
DISPLAY INVISIBLE (-5100 2400);
FORCEPROP 1 LASTPIN (-5650 2350) $PN 1
J 0
(-5638 2362);
DISPLAY 0.787234 (-5638 2362);
PAINT MONO (-5638 2362);
FORCEPROP 1 LASTPIN (-5450 2350) $PN 2
J 0
(-5488 2362);
DISPLAY 0.787234 (-5488 2362);
PAINT MONO (-5488 2362);
FORCEPROP 1 LAST VALUE 4.7K
J 2
(-5275 2350);
DISPLAY 0.638298 (-5275 2350);
FORCEPROP 1 LAST MATERIAL CHIP
J 0
(-5250 2350);
DISPLAY 0.638298 (-5250 2350);
FORCEPROP 1 LAST PACK_TYPE 0201LF
J 0
(-5100 2350);
DISPLAY 0.638298 (-5100 2350);
FORCEPROP 1 LAST WATTAGE 1/20W
J 2
(-5275 2525);
DISPLAY 0.978723 (-5275 2525);
DISPLAY INVISIBLE (-5275 2525);
FORCEPROP 1 LAST TOLERANCE 5%
J 0
(-5750 2525);
DISPLAY 0.978723 (-5750 2525);
DISPLAY INVISIBLE (-5750 2525);
FORCEPROP 2 LAST CDS_LIB pure_quanta
J 0
(-5550 2350);
DISPLAY INVISIBLE (-5550 2350);
FORCEPROP 1 LAST PATH I127
J 0
(-5600 2500);
DISPLAY 0.978723 (-5600 2500);
PAINT WHITE (-5600 2500);
DISPLAY INVISIBLE (-5600 2500);
FORCEPROP 1 LAST PART_NUMBER CS24701JE04
J 0
(-5775 2450);
DISPLAY 0.978723 (-5775 2450);
DISPLAY INVISIBLE (-5775 2450);
FORCEADD Q_RES..1
(-5550 2300);
FORCEPROP 1 LAST LOCATION R1383
J 0
(-5825 2300);
DISPLAY 0.787234 (-5825 2300);
FORCEPROP 0 LAST $SEC 1
J 0
(-5100 2350);
DISPLAY 0.680851 (-5100 2350);
PAINT MONO (-5100 2350);
DISPLAY INVISIBLE (-5100 2350);
FORCEPROP 0 LAST CDS_SEC 1
J 0
(-5100 2350);
DISPLAY 0.680851 (-5100 2350);
DISPLAY INVISIBLE (-5100 2350);
FORCEPROP 1 LASTPIN (-5650 2300) $PN 1
J 0
(-5638 2312);
DISPLAY 0.787234 (-5638 2312);
PAINT MONO (-5638 2312);
FORCEPROP 1 LASTPIN (-5450 2300) $PN 2
J 0
(-5488 2312);
DISPLAY 0.787234 (-5488 2312);
PAINT MONO (-5488 2312);
FORCEPROP 1 LAST VALUE 4.7K
J 2
(-5275 2300);
DISPLAY 0.638298 (-5275 2300);
FORCEPROP 1 LAST MATERIAL CHIP
J 0
(-5250 2300);
DISPLAY 0.638298 (-5250 2300);
FORCEPROP 1 LAST PACK_TYPE 0201LF
J 0
(-5100 2300);
DISPLAY 0.638298 (-5100 2300);
FORCEPROP 1 LAST WATTAGE 1/20W
J 2
(-5275 2475);
DISPLAY 0.978723 (-5275 2475);
DISPLAY INVISIBLE (-5275 2475);
FORCEPROP 1 LAST TOLERANCE 5%
J 0
(-5750 2475);
DISPLAY 0.978723 (-5750 2475);
DISPLAY INVISIBLE (-5750 2475);
FORCEPROP 2 LAST CDS_LIB pure_quanta
J 0
(-5550 2300);
DISPLAY INVISIBLE (-5550 2300);
FORCEPROP 1 LAST PATH I128
J 0
(-5600 2450);
DISPLAY 0.978723 (-5600 2450);
PAINT WHITE (-5600 2450);
DISPLAY INVISIBLE (-5600 2450);
FORCEPROP 1 LAST PART_NUMBER CS24701JE04
J 0
(-5775 2400);
DISPLAY 0.978723 (-5775 2400);
DISPLAY INVISIBLE (-5775 2400);
FORCEADD P1V0..1
(-6150 2925);
FORCEPROP 3 LASTPIN (-6150 2875) SIG_NAME P1V8_CPU0_RT_1D\g
J 0
(-6140 2885);
DISPLAY 0.659574 (-6140 2885);
PAINT MONO (-6140 2885);
DISPLAY INVISIBLE (-6140 2885);
FORCEPROP 1 LAST HDL_POWER P1V8_CPU0_RT_1D
J 1
(-6150 2975);
DISPLAY 0.957447 (-6150 2975);
PAINT SKYBLUE (-6150 2975);
FORCEPROP 2 LAST CDS_LIB pure_quanta_power
J 0
(-6150 2925);
DISPLAY INVISIBLE (-6150 2925);
FORCEPROP 1 LAST PATH I129
J 0
(-6100 2950);
DISPLAY 0.872340 (-6100 2950);
PAINT AQUA (-6100 2950);
DISPLAY INVISIBLE (-6100 2950);
FORCEADD P1V0..1
(-6400 2100);
FORCEPROP 3 LASTPIN (-6400 2050) SIG_NAME P1V8_CPU0_RT_1D\g
J 0
(-6390 2060);
DISPLAY 0.659574 (-6390 2060);
PAINT MONO (-6390 2060);
DISPLAY INVISIBLE (-6390 2060);
FORCEPROP 1 LAST HDL_POWER P1V8_CPU0_RT_1D
J 1
(-6400 2150);
DISPLAY 0.957447 (-6400 2150);
PAINT SKYBLUE (-6400 2150);
FORCEPROP 2 LAST CDS_LIB pure_quanta_power
J 0
(-6400 2100);
DISPLAY INVISIBLE (-6400 2100);
FORCEPROP 1 LAST PATH I13
J 0
(-6350 2125);
DISPLAY 0.872340 (-6350 2125);
PAINT AQUA (-6350 2125);
DISPLAY INVISIBLE (-6350 2125);
FORCEADD OFFPAGE..2
(-3900 3475);
FORCEPROP 2 LAST $XR1 310 
J 0
(-3591 3475);
DISPLAY 0.638298 (-3591 3475);
PAINT MONO (-3591 3475);
FORCEPROP 2 LAST $XR0 186 
J 0
(-3711 3475);
DISPLAY 0.638298 (-3711 3475);
PAINT MONO (-3711 3475);
FORCEPROP 2 LAST CDS_LIB standard
J 0
(-3900 3475);
DISPLAY INVISIBLE (-3900 3475);
FORCEPROP 1 LAST OFFPAGE TRUE
J 0
(-3575 3350);
DISPLAY 0.872340 (-3575 3350);
PAINT GREEN (-3575 3350);
DISPLAY INVISIBLE (-3575 3350);
FORCEPROP 1 LAST COMMENT_BODY TRUE
J 0
(-3945 3380);
DISPLAY 0.872340 (-3945 3380);
PAINT GREEN (-3945 3380);
DISPLAY INVISIBLE (-3945 3380);
FORCEPROP 2 LAST PATH I131
J 0
(-3700 3525);
DISPLAY 0.680851 (-3700 3525);
DISPLAY INVISIBLE (-3700 3525);
FORCEADD OFFPAGE..2
(-3900 3525);
FORCEPROP 2 LAST $XR1 186 
J 0
(-3591 3525);
DISPLAY 0.638298 (-3591 3525);
PAINT MONO (-3591 3525);
FORCEPROP 2 LAST $XR0 288 
J 0
(-3711 3525);
DISPLAY 0.638298 (-3711 3525);
PAINT MONO (-3711 3525);
FORCEPROP 2 LAST CDS_LIB standard
J 0
(-3900 3525);
DISPLAY INVISIBLE (-3900 3525);
FORCEPROP 1 LAST OFFPAGE TRUE
J 0
(-3575 3400);
DISPLAY 0.872340 (-3575 3400);
PAINT GREEN (-3575 3400);
DISPLAY INVISIBLE (-3575 3400);
FORCEPROP 1 LAST COMMENT_BODY TRUE
J 0
(-3945 3430);
DISPLAY 0.872340 (-3945 3430);
PAINT GREEN (-3945 3430);
DISPLAY INVISIBLE (-3945 3430);
FORCEPROP 2 LAST PATH I132
J 0
(-3700 3575);
DISPLAY 0.680851 (-3700 3575);
DISPLAY INVISIBLE (-3700 3575);
FORCEADD OFFPAGE..2
(-700 3350);
FORCEPROP 2 LAST $XR1 343 
J 0
(-391 3350);
DISPLAY 0.638298 (-391 3350);
PAINT MONO (-391 3350);
FORCEPROP 2 LAST $XR0 186 
J 0
(-511 3350);
DISPLAY 0.638298 (-511 3350);
PAINT MONO (-511 3350);
FORCEPROP 2 LAST CDS_LIB standard
J 0
(-700 3350);
DISPLAY INVISIBLE (-700 3350);
FORCEPROP 1 LAST OFFPAGE TRUE
J 0
(-375 3225);
DISPLAY 0.872340 (-375 3225);
PAINT GREEN (-375 3225);
DISPLAY INVISIBLE (-375 3225);
FORCEPROP 1 LAST COMMENT_BODY TRUE
J 0
(-745 3255);
DISPLAY 0.872340 (-745 3255);
PAINT GREEN (-745 3255);
DISPLAY INVISIBLE (-745 3255);
FORCEPROP 2 LAST PATH I134
J 0
(-500 3400);
DISPLAY 0.680851 (-500 3400);
DISPLAY INVISIBLE (-500 3400);
FORCEADD OFFPAGE..2
(-700 3650);
FORCEPROP 2 LAST $XR1 321 
J 0
(-391 3650);
DISPLAY 0.638298 (-391 3650);
PAINT MONO (-391 3650);
FORCEPROP 2 LAST $XR0 186 
J 0
(-511 3650);
DISPLAY 0.638298 (-511 3650);
PAINT MONO (-511 3650);
FORCEPROP 2 LAST CDS_LIB standard
J 0
(-700 3650);
DISPLAY INVISIBLE (-700 3650);
FORCEPROP 1 LAST OFFPAGE TRUE
J 0
(-375 3525);
DISPLAY 0.872340 (-375 3525);
PAINT GREEN (-375 3525);
DISPLAY INVISIBLE (-375 3525);
FORCEPROP 1 LAST COMMENT_BODY TRUE
J 0
(-745 3555);
DISPLAY 0.872340 (-745 3555);
PAINT GREEN (-745 3555);
DISPLAY INVISIBLE (-745 3555);
FORCEPROP 2 LAST PATH I135
J 0
(-500 3700);
DISPLAY 0.680851 (-500 3700);
DISPLAY INVISIBLE (-500 3700);
FORCEADD OFFPAGE..2
(-700 3600);
FORCEPROP 2 LAST $XR1 186 
J 0
(-391 3600);
DISPLAY 0.638298 (-391 3600);
PAINT MONO (-391 3600);
FORCEPROP 2 LAST $XR0 321 
J 0
(-511 3600);
DISPLAY 0.638298 (-511 3600);
PAINT MONO (-511 3600);
FORCEPROP 2 LAST CDS_LIB standard
J 0
(-700 3600);
DISPLAY INVISIBLE (-700 3600);
FORCEPROP 1 LAST OFFPAGE TRUE
J 0
(-375 3475);
DISPLAY 0.872340 (-375 3475);
PAINT GREEN (-375 3475);
DISPLAY INVISIBLE (-375 3475);
FORCEPROP 1 LAST COMMENT_BODY TRUE
J 0
(-745 3505);
DISPLAY 0.872340 (-745 3505);
PAINT GREEN (-745 3505);
DISPLAY INVISIBLE (-745 3505);
FORCEPROP 2 LAST PATH I136
J 0
(-500 3650);
DISPLAY 0.680851 (-500 3650);
DISPLAY INVISIBLE (-500 3650);
FORCEADD OFFPAGE..2
(-700 3550);
FORCEPROP 2 LAST $XR1 332 
J 0
(-391 3550);
DISPLAY 0.638298 (-391 3550);
PAINT MONO (-391 3550);
FORCEPROP 2 LAST $XR0 186 
J 0
(-511 3550);
DISPLAY 0.638298 (-511 3550);
PAINT MONO (-511 3550);
FORCEPROP 2 LAST CDS_LIB standard
J 0
(-700 3550);
DISPLAY INVISIBLE (-700 3550);
FORCEPROP 1 LAST OFFPAGE TRUE
J 0
(-375 3425);
DISPLAY 0.872340 (-375 3425);
PAINT GREEN (-375 3425);
DISPLAY INVISIBLE (-375 3425);
FORCEPROP 1 LAST COMMENT_BODY TRUE
J 0
(-745 3455);
DISPLAY 0.872340 (-745 3455);
PAINT GREEN (-745 3455);
DISPLAY INVISIBLE (-745 3455);
FORCEPROP 2 LAST PATH I137
J 0
(-500 3600);
DISPLAY 0.680851 (-500 3600);
DISPLAY INVISIBLE (-500 3600);
FORCEADD OFFPAGE..2
(-700 3500);
FORCEPROP 2 LAST $XR1 186 
J 0
(-391 3500);
DISPLAY 0.638298 (-391 3500);
PAINT MONO (-391 3500);
FORCEPROP 2 LAST $XR0 332 
J 0
(-511 3500);
DISPLAY 0.638298 (-511 3500);
PAINT MONO (-511 3500);
FORCEPROP 2 LAST CDS_LIB standard
J 0
(-700 3500);
DISPLAY INVISIBLE (-700 3500);
FORCEPROP 1 LAST OFFPAGE TRUE
J 0
(-375 3375);
DISPLAY 0.872340 (-375 3375);
PAINT GREEN (-375 3375);
DISPLAY INVISIBLE (-375 3375);
FORCEPROP 1 LAST COMMENT_BODY TRUE
J 0
(-745 3405);
DISPLAY 0.872340 (-745 3405);
PAINT GREEN (-745 3405);
DISPLAY INVISIBLE (-745 3405);
FORCEPROP 2 LAST PATH I138
J 0
(-500 3550);
DISPLAY 0.680851 (-500 3550);
DISPLAY INVISIBLE (-500 3550);
FORCEADD OFFPAGE..2
(-700 3450);
FORCEPROP 2 LAST $XR1 354 
J 0
(-391 3450);
DISPLAY 0.638298 (-391 3450);
PAINT MONO (-391 3450);
FORCEPROP 2 LAST $XR0 186 
J 0
(-511 3450);
DISPLAY 0.638298 (-511 3450);
PAINT MONO (-511 3450);
FORCEPROP 2 LAST CDS_LIB standard
J 0
(-700 3450);
DISPLAY INVISIBLE (-700 3450);
FORCEPROP 1 LAST OFFPAGE TRUE
J 0
(-375 3325);
DISPLAY 0.872340 (-375 3325);
PAINT GREEN (-375 3325);
DISPLAY INVISIBLE (-375 3325);
FORCEPROP 1 LAST COMMENT_BODY TRUE
J 0
(-745 3355);
DISPLAY 0.872340 (-745 3355);
PAINT GREEN (-745 3355);
DISPLAY INVISIBLE (-745 3355);
FORCEPROP 2 LAST PATH I139
J 0
(-500 3500);
DISPLAY 0.680851 (-500 3500);
DISPLAY INVISIBLE (-500 3500);
FORCEADD OFFPAGE..1
(-8450 3550);
FORCEPROP 2 LAST $XR2 186 
J 0
(-8911 3550);
DISPLAY 0.638298 (-8911 3550);
PAINT MONO (-8911 3550);
FORCEPROP 2 LAST $XR1 185 
J 0
(-8791 3550);
DISPLAY 0.638298 (-8791 3550);
PAINT MONO (-8791 3550);
FORCEPROP 2 LAST $XR0 81 
J 0
(-8671 3550);
DISPLAY 0.638298 (-8671 3550);
PAINT MONO (-8671 3550);
FORCEPROP 2 LAST CDS_LIB standard
J 0
(-8450 3550);
DISPLAY INVISIBLE (-8450 3550);
FORCEPROP 1 LAST OFFPAGE TRUE
J 0
(-8125 3425);
DISPLAY 1.170213 (-8125 3425);
PAINT GREEN (-8125 3425);
DISPLAY INVISIBLE (-8125 3425);
FORCEPROP 1 LAST COMMENT_BODY TRUE
J 0
(-8325 3450);
DISPLAY 1.170213 (-8325 3450);
PAINT GREEN (-8325 3450);
DISPLAY INVISIBLE (-8325 3450);
FORCEPROP 2 LAST PATH I14
J 0
(-8650 3600);
DISPLAY 0.680851 (-8650 3600);
DISPLAY INVISIBLE (-8650 3600);
FORCEADD OFFPAGE..2
(-700 3400);
FORCEPROP 2 LAST $XR1 186 
J 0
(-391 3400);
DISPLAY 0.638298 (-391 3400);
PAINT MONO (-391 3400);
FORCEPROP 2 LAST $XR0 354 
J 0
(-511 3400);
DISPLAY 0.638298 (-511 3400);
PAINT MONO (-511 3400);
FORCEPROP 2 LAST CDS_LIB standard
J 0
(-700 3400);
DISPLAY INVISIBLE (-700 3400);
FORCEPROP 1 LAST OFFPAGE TRUE
J 0
(-375 3275);
DISPLAY 0.872340 (-375 3275);
PAINT GREEN (-375 3275);
DISPLAY INVISIBLE (-375 3275);
FORCEPROP 1 LAST COMMENT_BODY TRUE
J 0
(-745 3305);
DISPLAY 0.872340 (-745 3305);
PAINT GREEN (-745 3305);
DISPLAY INVISIBLE (-745 3305);
FORCEPROP 2 LAST PATH I140
J 0
(-500 3450);
DISPLAY 0.680851 (-500 3450);
DISPLAY INVISIBLE (-500 3450);
FORCEADD OFFPAGE..2
(-700 3300);
FORCEPROP 2 LAST $XR1 186 
J 0
(-391 3300);
DISPLAY 0.638298 (-391 3300);
PAINT MONO (-391 3300);
FORCEPROP 2 LAST $XR0 343 
J 0
(-511 3300);
DISPLAY 0.638298 (-511 3300);
PAINT MONO (-511 3300);
FORCEPROP 2 LAST CDS_LIB standard
J 0
(-700 3300);
DISPLAY INVISIBLE (-700 3300);
FORCEPROP 1 LAST OFFPAGE TRUE
J 0
(-375 3175);
DISPLAY 0.872340 (-375 3175);
PAINT GREEN (-375 3175);
DISPLAY INVISIBLE (-375 3175);
FORCEPROP 1 LAST COMMENT_BODY TRUE
J 0
(-745 3205);
DISPLAY 0.872340 (-745 3205);
PAINT GREEN (-745 3205);
DISPLAY INVISIBLE (-745 3205);
FORCEPROP 2 LAST PATH I141
J 0
(-500 3350);
DISPLAY 0.680851 (-500 3350);
DISPLAY INVISIBLE (-500 3350);
FORCEADD P1V0..1
(-3200 4000);
FORCEPROP 3 LASTPIN (-3200 3950) SIG_NAME P1V8_CPU1_RT_1D\g
J 0
(-3190 3960);
DISPLAY 0.659574 (-3190 3960);
PAINT MONO (-3190 3960);
DISPLAY INVISIBLE (-3190 3960);
FORCEPROP 1 LAST HDL_POWER P1V8_CPU1_RT_1D
J 1
(-3200 4050);
DISPLAY 0.957447 (-3200 4050);
PAINT SKYBLUE (-3200 4050);
FORCEPROP 2 LAST CDS_LIB pure_quanta_power
J 0
(-3200 4000);
DISPLAY INVISIBLE (-3200 4000);
FORCEPROP 1 LAST PATH I148
J 0
(-3150 4025);
DISPLAY 0.872340 (-3150 4025);
PAINT AQUA (-3150 4025);
DISPLAY INVISIBLE (-3150 4025);
FORCEADD OFFPAGE..2
(-3900 3675);
FORCEPROP 2 LAST $XR1 277 
J 0
(-3591 3675);
DISPLAY 0.638298 (-3591 3675);
PAINT MONO (-3591 3675);
FORCEPROP 2 LAST $XR0 186 
J 0
(-3711 3675);
DISPLAY 0.638298 (-3711 3675);
PAINT MONO (-3711 3675);
FORCEPROP 2 LAST CDS_LIB standard
J 0
(-3900 3675);
DISPLAY INVISIBLE (-3900 3675);
FORCEPROP 1 LAST OFFPAGE TRUE
J 0
(-3575 3550);
DISPLAY 0.872340 (-3575 3550);
PAINT GREEN (-3575 3550);
DISPLAY INVISIBLE (-3575 3550);
FORCEPROP 1 LAST COMMENT_BODY TRUE
J 0
(-3945 3580);
DISPLAY 0.872340 (-3945 3580);
PAINT GREEN (-3945 3580);
DISPLAY INVISIBLE (-3945 3580);
FORCEPROP 2 LAST PATH I149
J 0
(-3700 3725);
DISPLAY 0.680851 (-3700 3725);
DISPLAY INVISIBLE (-3700 3725);
FORCEADD UNIVERSAL_GND..1
(-7750 2925);
FORCEPROP 3 LASTPIN (-7750 2975) SIG_NAME GND\g
J 0
(-7740 2985);
DISPLAY 0.659574 (-7740 2985);
PAINT MONO (-7740 2985);
DISPLAY INVISIBLE (-7740 2985);
FORCEPROP 2 LAST CDS_LIB pure_quanta_power
J 0
(-7750 2925);
DISPLAY INVISIBLE (-7750 2925);
FORCEPROP 1 LAST HDL_POWER GND
J 1
(-7725 2850);
DISPLAY 0.872340 (-7725 2850);
PAINT GREEN (-7725 2850);
DISPLAY INVISIBLE (-7725 2850);
FORCEPROP 1 LAST PATH I15
J 0
(-7675 2925);
DISPLAY 0.872340 (-7675 2925);
PAINT AQUA (-7675 2925);
DISPLAY INVISIBLE (-7675 2925);
FORCEADD OFFPAGE..2
(-3900 3625);
FORCEPROP 2 LAST $XR1 186 
J 0
(-3591 3625);
DISPLAY 0.638298 (-3591 3625);
PAINT MONO (-3591 3625);
FORCEPROP 2 LAST $XR0 277 
J 0
(-3711 3625);
DISPLAY 0.638298 (-3711 3625);
PAINT MONO (-3711 3625);
FORCEPROP 2 LAST CDS_LIB standard
J 0
(-3900 3625);
DISPLAY INVISIBLE (-3900 3625);
FORCEPROP 1 LAST OFFPAGE TRUE
J 0
(-3575 3500);
DISPLAY 0.872340 (-3575 3500);
PAINT GREEN (-3575 3500);
DISPLAY INVISIBLE (-3575 3500);
FORCEPROP 1 LAST COMMENT_BODY TRUE
J 0
(-3945 3530);
DISPLAY 0.872340 (-3945 3530);
PAINT GREEN (-3945 3530);
DISPLAY INVISIBLE (-3945 3530);
FORCEPROP 2 LAST PATH I150
J 0
(-3700 3675);
DISPLAY 0.680851 (-3700 3675);
DISPLAY INVISIBLE (-3700 3675);
FORCEADD OFFPAGE..2
(-3900 3575);
FORCEPROP 2 LAST $XR1 288 
J 0
(-3591 3575);
DISPLAY 0.638298 (-3591 3575);
PAINT MONO (-3591 3575);
FORCEPROP 2 LAST $XR0 186 
J 0
(-3711 3575);
DISPLAY 0.638298 (-3711 3575);
PAINT MONO (-3711 3575);
FORCEPROP 2 LAST CDS_LIB standard
J 0
(-3900 3575);
DISPLAY INVISIBLE (-3900 3575);
FORCEPROP 1 LAST OFFPAGE TRUE
J 0
(-3575 3450);
DISPLAY 0.872340 (-3575 3450);
PAINT GREEN (-3575 3450);
DISPLAY INVISIBLE (-3575 3450);
FORCEPROP 1 LAST COMMENT_BODY TRUE
J 0
(-3945 3480);
DISPLAY 0.872340 (-3945 3480);
PAINT GREEN (-3945 3480);
DISPLAY INVISIBLE (-3945 3480);
FORCEPROP 2 LAST PATH I151
J 0
(-3700 3625);
DISPLAY 0.680851 (-3700 3625);
DISPLAY INVISIBLE (-3700 3625);
FORCEADD OFFPAGE..2
(-3900 3375);
FORCEPROP 2 LAST $XR1 299 
J 0
(-3591 3375);
DISPLAY 0.638298 (-3591 3375);
PAINT MONO (-3591 3375);
FORCEPROP 2 LAST $XR0 186 
J 0
(-3711 3375);
DISPLAY 0.638298 (-3711 3375);
PAINT MONO (-3711 3375);
FORCEPROP 2 LAST CDS_LIB standard
J 0
(-3900 3375);
DISPLAY INVISIBLE (-3900 3375);
FORCEPROP 1 LAST OFFPAGE TRUE
J 0
(-3575 3250);
DISPLAY 0.872340 (-3575 3250);
PAINT GREEN (-3575 3250);
DISPLAY INVISIBLE (-3575 3250);
FORCEPROP 1 LAST COMMENT_BODY TRUE
J 0
(-3945 3280);
DISPLAY 0.872340 (-3945 3280);
PAINT GREEN (-3945 3280);
DISPLAY INVISIBLE (-3945 3280);
FORCEPROP 2 LAST PATH I152
J 0
(-3700 3425);
DISPLAY 0.680851 (-3700 3425);
DISPLAY INVISIBLE (-3700 3425);
FORCEADD OFFPAGE..2
(-3900 3425);
FORCEPROP 2 LAST $XR1 186 
J 0
(-3591 3425);
DISPLAY 0.638298 (-3591 3425);
PAINT MONO (-3591 3425);
FORCEPROP 2 LAST $XR0 310 
J 0
(-3711 3425);
DISPLAY 0.638298 (-3711 3425);
PAINT MONO (-3711 3425);
FORCEPROP 2 LAST CDS_LIB standard
J 0
(-3900 3425);
DISPLAY INVISIBLE (-3900 3425);
FORCEPROP 1 LAST OFFPAGE TRUE
J 0
(-3575 3300);
DISPLAY 0.872340 (-3575 3300);
PAINT GREEN (-3575 3300);
DISPLAY INVISIBLE (-3575 3300);
FORCEPROP 1 LAST COMMENT_BODY TRUE
J 0
(-3945 3330);
DISPLAY 0.872340 (-3945 3330);
PAINT GREEN (-3945 3330);
DISPLAY INVISIBLE (-3945 3330);
FORCEPROP 2 LAST PATH I153
J 0
(-3700 3475);
DISPLAY 0.680851 (-3700 3475);
DISPLAY INVISIBLE (-3700 3475);
FORCEADD OFFPAGE..2
(-3900 3325);
FORCEPROP 2 LAST $XR1 186 
J 0
(-3591 3325);
DISPLAY 0.638298 (-3591 3325);
PAINT MONO (-3591 3325);
FORCEPROP 2 LAST $XR0 299 
J 0
(-3711 3325);
DISPLAY 0.638298 (-3711 3325);
PAINT MONO (-3711 3325);
FORCEPROP 2 LAST CDS_LIB standard
J 0
(-3900 3325);
DISPLAY INVISIBLE (-3900 3325);
FORCEPROP 1 LAST OFFPAGE TRUE
J 0
(-3575 3200);
DISPLAY 0.872340 (-3575 3200);
PAINT GREEN (-3575 3200);
DISPLAY INVISIBLE (-3575 3200);
FORCEPROP 1 LAST COMMENT_BODY TRUE
J 0
(-3945 3230);
DISPLAY 0.872340 (-3945 3230);
PAINT GREEN (-3945 3230);
DISPLAY INVISIBLE (-3945 3230);
FORCEPROP 2 LAST PATH I154
J 0
(-3700 3375);
DISPLAY 0.680851 (-3700 3375);
DISPLAY INVISIBLE (-3700 3375);
FORCEADD Q_RES..2
(-7750 3300);
FORCEPROP 1 LAST LOCATION R849
J 0
(-7705 3425);
DISPLAY 0.978723 (-7705 3425);
FORCEPROP 0 LAST $SEC 1
J 0
(-7700 3475);
DISPLAY 0.680851 (-7700 3475);
PAINT MONO (-7700 3475);
DISPLAY INVISIBLE (-7700 3475);
FORCEPROP 0 LAST CDS_SEC 1
J 0
(-7700 3475);
DISPLAY 0.680851 (-7700 3475);
DISPLAY INVISIBLE (-7700 3475);
FORCEPROP 1 LASTPIN (-7750 3400) $PN 1
J 0
(-7745 3362);
DISPLAY 0.787234 (-7745 3362);
PAINT MONO (-7745 3362);
FORCEPROP 1 LASTPIN (-7750 3200) $PN 2
J 0
(-7745 3210);
DISPLAY 0.787234 (-7745 3210);
PAINT MONO (-7745 3210);
FORCEPROP 1 LAST PACK_TYPE 0201LF
J 0
(-7710 3125);
DISPLAY 0.978723 (-7710 3125);
FORCEPROP 1 LAST WATTAGE 1/20W
J 0
(-7710 3275);
DISPLAY 0.978723 (-7710 3275);
FORCEPROP 1 LAST VALUE 10K
J 0
(-7705 3375);
DISPLAY 0.978723 (-7705 3375);
FORCEPROP 1 LAST TOLERANCE 1%
J 0
(-7705 3325);
DISPLAY 0.978723 (-7705 3325);
FORCEPROP 1 LAST MATERIAL CHIP
J 0
(-7710 3225);
DISPLAY 0.978723 (-7710 3225);
FORCEPROP 2 LAST CDS_LIB pure_quanta
J 0
(-7750 3300);
DISPLAY INVISIBLE (-7750 3300);
FORCEPROP 1 LAST PATH I16
J 0
(-7700 3475);
DISPLAY 0.978723 (-7700 3475);
PAINT WHITE (-7700 3475);
DISPLAY INVISIBLE (-7700 3475);
FORCEPROP 1 LAST PART_NUMBER CS31001FE17
J 0
(-7710 3175);
DISPLAY 0.978723 (-7710 3175);
DISPLAY INVISIBLE (-7710 3175);
FORCEADD P1V0..1
(-6325 3950);
FORCEPROP 3 LASTPIN (-6325 3900) SIG_NAME P1V8_CPU0_RT_1D\g
J 0
(-6315 3910);
DISPLAY 0.659574 (-6315 3910);
PAINT MONO (-6315 3910);
DISPLAY INVISIBLE (-6315 3910);
FORCEPROP 1 LAST HDL_POWER P1V8_CPU0_RT_1D
J 1
(-6325 4000);
DISPLAY 0.957447 (-6325 4000);
PAINT SKYBLUE (-6325 4000);
FORCEPROP 2 LAST CDS_LIB pure_quanta_power
J 0
(-6325 3950);
DISPLAY INVISIBLE (-6325 3950);
FORCEPROP 1 LAST PATH I163
J 0
(-6275 3975);
DISPLAY 0.872340 (-6275 3975);
PAINT AQUA (-6275 3975);
DISPLAY INVISIBLE (-6275 3975);
FORCEADD Q_RES..1
(-5725 3675);
FORCEPROP 1 LAST LOCATION R1410
J 0
(-6025 3675);
DISPLAY 0.978723 (-6025 3675);
PAINT SKYBLUE (-6025 3675);
FORCEPROP 0 LAST $SEC 1
J 0
(-5350 3925);
DISPLAY 0.680851 (-5350 3925);
PAINT MONO (-5350 3925);
DISPLAY INVISIBLE (-5350 3925);
FORCEPROP 0 LAST CDS_SEC 1
J 0
(-5350 3925);
DISPLAY 0.680851 (-5350 3925);
DISPLAY INVISIBLE (-5350 3925);
FORCEPROP 1 LASTPIN (-5825 3675) $PN 1
J 0
(-5813 3687);
DISPLAY 0.787234 (-5813 3687);
PAINT MONO (-5813 3687);
FORCEPROP 1 LASTPIN (-5625 3675) $PN 2
J 0
(-5663 3687);
DISPLAY 0.787234 (-5663 3687);
PAINT MONO (-5663 3687);
FORCEPROP 1 LAST MATERIAL CHIP
J 0
(-5425 3675);
DISPLAY 0.787234 (-5425 3675);
FORCEPROP 1 LAST VALUE 1K
J 2
(-5450 3675);
DISPLAY 0.787234 (-5450 3675);
FORCEPROP 1 LAST TOLERANCE 1%
J 0
(-5750 3875);
DISPLAY 0.978723 (-5750 3875);
FORCEPROP 1 LAST WATTAGE 1/20W
J 2
(-5350 3875);
DISPLAY 0.978723 (-5350 3875);
FORCEPROP 1 LAST PACK_TYPE 0201LF
J 0
(-5200 3675);
DISPLAY 0.787234 (-5200 3675);
FORCEPROP 2 LAST CDS_LIB pure_quanta
J 0
(-5725 3675);
DISPLAY INVISIBLE (-5725 3675);
FORCEPROP 1 LAST PATH I164
J 0
(-5775 3825);
DISPLAY 0.978723 (-5775 3825);
PAINT WHITE (-5775 3825);
DISPLAY INVISIBLE (-5775 3825);
FORCEPROP 1 LAST PART_NUMBER CS21001FE07
J 0
(-5775 3775);
DISPLAY 0.978723 (-5775 3775);
DISPLAY INVISIBLE (-5775 3775);
FORCEADD Q_RES..1
(-5725 3625);
FORCEPROP 1 LAST LOCATION R1411
J 0
(-6025 3625);
DISPLAY 0.978723 (-6025 3625);
FORCEPROP 0 LAST $SEC 1
J 0
(-5200 3675);
DISPLAY 0.680851 (-5200 3675);
PAINT MONO (-5200 3675);
DISPLAY INVISIBLE (-5200 3675);
FORCEPROP 0 LAST CDS_SEC 1
J 0
(-5200 3675);
DISPLAY 0.680851 (-5200 3675);
DISPLAY INVISIBLE (-5200 3675);
FORCEPROP 1 LASTPIN (-5825 3625) $PN 1
J 0
(-5813 3637);
DISPLAY 0.787234 (-5813 3637);
PAINT MONO (-5813 3637);
FORCEPROP 1 LASTPIN (-5625 3625) $PN 2
J 0
(-5663 3637);
DISPLAY 0.787234 (-5663 3637);
PAINT MONO (-5663 3637);
FORCEPROP 1 LAST PACK_TYPE 0201LF
J 0
(-5200 3625);
DISPLAY 0.787234 (-5200 3625);
FORCEPROP 1 LAST MATERIAL CHIP
J 0
(-5425 3625);
DISPLAY 0.787234 (-5425 3625);
FORCEPROP 1 LAST VALUE 1K
J 2
(-5450 3625);
DISPLAY 0.787234 (-5450 3625);
FORCEPROP 2 LAST CDS_LIB pure_quanta
J 0
(-5725 3625);
DISPLAY INVISIBLE (-5725 3625);
FORCEPROP 1 LAST TOLERANCE 1%
J 0
(-5750 3825);
DISPLAY 0.787234 (-5750 3825);
DISPLAY INVISIBLE (-5750 3825);
FORCEPROP 1 LAST WATTAGE 1/20W
J 2
(-5350 3825);
DISPLAY 0.787234 (-5350 3825);
DISPLAY INVISIBLE (-5350 3825);
FORCEPROP 1 LAST PATH I165
J 0
(-5775 3775);
DISPLAY 0.978723 (-5775 3775);
PAINT WHITE (-5775 3775);
DISPLAY INVISIBLE (-5775 3775);
FORCEPROP 1 LAST PART_NUMBER CS21001FE07
J 0
(-5775 3725);
DISPLAY 0.787234 (-5775 3725);
DISPLAY INVISIBLE (-5775 3725);
FORCEADD Q_RES..1
(-5725 3575);
FORCEPROP 1 LAST LOCATION R1415
J 0
(-6025 3575);
DISPLAY 0.978723 (-6025 3575);
FORCEPROP 0 LAST $SEC 1
J 0
(-5200 3625);
DISPLAY 0.680851 (-5200 3625);
PAINT MONO (-5200 3625);
DISPLAY INVISIBLE (-5200 3625);
FORCEPROP 0 LAST CDS_SEC 1
J 0
(-5200 3625);
DISPLAY 0.680851 (-5200 3625);
DISPLAY INVISIBLE (-5200 3625);
FORCEPROP 1 LASTPIN (-5825 3575) $PN 1
J 0
(-5813 3587);
DISPLAY 0.787234 (-5813 3587);
PAINT MONO (-5813 3587);
FORCEPROP 1 LASTPIN (-5625 3575) $PN 2
J 0
(-5663 3587);
DISPLAY 0.787234 (-5663 3587);
PAINT MONO (-5663 3587);
FORCEPROP 1 LAST VALUE 1K
J 2
(-5450 3575);
DISPLAY 0.787234 (-5450 3575);
FORCEPROP 1 LAST MATERIAL CHIP
J 0
(-5425 3575);
DISPLAY 0.787234 (-5425 3575);
FORCEPROP 1 LAST PACK_TYPE 0201LF
J 0
(-5200 3575);
DISPLAY 0.787234 (-5200 3575);
FORCEPROP 1 LAST WATTAGE 1/20W
J 2
(-5350 3775);
DISPLAY 0.787234 (-5350 3775);
DISPLAY INVISIBLE (-5350 3775);
FORCEPROP 1 LAST TOLERANCE 1%
J 0
(-5750 3775);
DISPLAY 0.787234 (-5750 3775);
DISPLAY INVISIBLE (-5750 3775);
FORCEPROP 2 LAST CDS_LIB pure_quanta
J 0
(-5725 3575);
DISPLAY INVISIBLE (-5725 3575);
FORCEPROP 1 LAST PATH I166
J 0
(-5775 3725);
DISPLAY 0.978723 (-5775 3725);
PAINT WHITE (-5775 3725);
DISPLAY INVISIBLE (-5775 3725);
FORCEPROP 1 LAST PART_NUMBER CS21001FE07
J 0
(-5775 3675);
DISPLAY 0.787234 (-5775 3675);
DISPLAY INVISIBLE (-5775 3675);
FORCEADD Q_RES..1
(-5725 3525);
FORCEPROP 1 LAST LOCATION R1418
J 0
(-6025 3525);
DISPLAY 0.978723 (-6025 3525);
FORCEPROP 0 LAST $SEC 1
J 0
(-5200 3575);
DISPLAY 0.680851 (-5200 3575);
PAINT MONO (-5200 3575);
DISPLAY INVISIBLE (-5200 3575);
FORCEPROP 0 LAST CDS_SEC 1
J 0
(-5200 3575);
DISPLAY 0.680851 (-5200 3575);
DISPLAY INVISIBLE (-5200 3575);
FORCEPROP 1 LASTPIN (-5825 3525) $PN 1
J 0
(-5813 3537);
DISPLAY 0.787234 (-5813 3537);
PAINT MONO (-5813 3537);
FORCEPROP 1 LASTPIN (-5625 3525) $PN 2
J 0
(-5663 3537);
DISPLAY 0.787234 (-5663 3537);
PAINT MONO (-5663 3537);
FORCEPROP 1 LAST VALUE 1K
J 2
(-5450 3525);
DISPLAY 0.787234 (-5450 3525);
FORCEPROP 1 LAST MATERIAL CHIP
J 0
(-5425 3525);
DISPLAY 0.787234 (-5425 3525);
FORCEPROP 1 LAST PACK_TYPE 0201LF
J 0
(-5200 3525);
DISPLAY 0.787234 (-5200 3525);
FORCEPROP 1 LAST WATTAGE 1/20W
J 2
(-5350 3725);
DISPLAY 0.787234 (-5350 3725);
DISPLAY INVISIBLE (-5350 3725);
FORCEPROP 1 LAST TOLERANCE 1%
J 0
(-5750 3725);
DISPLAY 0.787234 (-5750 3725);
DISPLAY INVISIBLE (-5750 3725);
FORCEPROP 2 LAST CDS_LIB pure_quanta
J 0
(-5725 3525);
DISPLAY INVISIBLE (-5725 3525);
FORCEPROP 1 LAST PATH I167
J 0
(-5775 3675);
DISPLAY 0.978723 (-5775 3675);
PAINT WHITE (-5775 3675);
DISPLAY INVISIBLE (-5775 3675);
FORCEPROP 1 LAST PART_NUMBER CS21001FE07
J 0
(-5775 3625);
DISPLAY 0.787234 (-5775 3625);
DISPLAY INVISIBLE (-5775 3625);
FORCEADD Q_RES..1
(-5725 3475);
FORCEPROP 1 LAST LOCATION R1420
J 0
(-6025 3475);
DISPLAY 0.978723 (-6025 3475);
FORCEPROP 0 LAST $SEC 1
J 0
(-5200 3525);
DISPLAY 0.680851 (-5200 3525);
PAINT MONO (-5200 3525);
DISPLAY INVISIBLE (-5200 3525);
FORCEPROP 0 LAST CDS_SEC 1
J 0
(-5200 3525);
DISPLAY 0.680851 (-5200 3525);
DISPLAY INVISIBLE (-5200 3525);
FORCEPROP 1 LASTPIN (-5825 3475) $PN 1
J 0
(-5813 3487);
DISPLAY 0.787234 (-5813 3487);
PAINT MONO (-5813 3487);
FORCEPROP 1 LASTPIN (-5625 3475) $PN 2
J 0
(-5663 3487);
DISPLAY 0.787234 (-5663 3487);
PAINT MONO (-5663 3487);
FORCEPROP 1 LAST VALUE 1K
J 2
(-5450 3475);
DISPLAY 0.787234 (-5450 3475);
FORCEPROP 1 LAST MATERIAL CHIP
J 0
(-5425 3475);
DISPLAY 0.787234 (-5425 3475);
FORCEPROP 1 LAST PACK_TYPE 0201LF
J 0
(-5200 3475);
DISPLAY 0.787234 (-5200 3475);
FORCEPROP 1 LAST WATTAGE 1/20W
J 2
(-5350 3675);
DISPLAY 0.787234 (-5350 3675);
DISPLAY INVISIBLE (-5350 3675);
FORCEPROP 1 LAST TOLERANCE 1%
J 0
(-5750 3675);
DISPLAY 0.787234 (-5750 3675);
DISPLAY INVISIBLE (-5750 3675);
FORCEPROP 2 LAST CDS_LIB pure_quanta
J 0
(-5725 3475);
DISPLAY INVISIBLE (-5725 3475);
FORCEPROP 1 LAST PATH I168
J 0
(-5775 3625);
DISPLAY 0.978723 (-5775 3625);
PAINT WHITE (-5775 3625);
DISPLAY INVISIBLE (-5775 3625);
FORCEPROP 1 LAST PART_NUMBER CS21001FE07
J 0
(-5775 3575);
DISPLAY 0.787234 (-5775 3575);
DISPLAY INVISIBLE (-5775 3575);
FORCEADD Q_RES..1
(-5725 3425);
FORCEPROP 1 LAST LOCATION R1428
J 0
(-6025 3425);
DISPLAY 0.978723 (-6025 3425);
FORCEPROP 0 LAST $SEC 1
J 0
(-5200 3475);
DISPLAY 0.680851 (-5200 3475);
PAINT MONO (-5200 3475);
DISPLAY INVISIBLE (-5200 3475);
FORCEPROP 0 LAST CDS_SEC 1
J 0
(-5200 3475);
DISPLAY 0.680851 (-5200 3475);
DISPLAY INVISIBLE (-5200 3475);
FORCEPROP 1 LASTPIN (-5825 3425) $PN 1
J 0
(-5813 3437);
DISPLAY 0.787234 (-5813 3437);
PAINT MONO (-5813 3437);
FORCEPROP 1 LASTPIN (-5625 3425) $PN 2
J 0
(-5663 3437);
DISPLAY 0.787234 (-5663 3437);
PAINT MONO (-5663 3437);
FORCEPROP 1 LAST MATERIAL CHIP
J 0
(-5425 3425);
DISPLAY 0.787234 (-5425 3425);
FORCEPROP 1 LAST VALUE 1K
J 2
(-5450 3425);
DISPLAY 0.787234 (-5450 3425);
FORCEPROP 1 LAST PACK_TYPE 0201LF
J 0
(-5200 3425);
DISPLAY 0.787234 (-5200 3425);
FORCEPROP 1 LAST WATTAGE 1/20W
J 2
(-5350 3625);
DISPLAY 0.787234 (-5350 3625);
DISPLAY INVISIBLE (-5350 3625);
FORCEPROP 1 LAST TOLERANCE 1%
J 0
(-5750 3625);
DISPLAY 0.787234 (-5750 3625);
DISPLAY INVISIBLE (-5750 3625);
FORCEPROP 2 LAST CDS_LIB pure_quanta
J 0
(-5725 3425);
DISPLAY INVISIBLE (-5725 3425);
FORCEPROP 1 LAST PATH I169
J 0
(-5775 3575);
DISPLAY 0.978723 (-5775 3575);
PAINT WHITE (-5775 3575);
DISPLAY INVISIBLE (-5775 3575);
FORCEPROP 1 LAST PART_NUMBER CS21001FE07
J 0
(-5775 3525);
DISPLAY 0.787234 (-5775 3525);
DISPLAY INVISIBLE (-5775 3525);
FORCEADD Q_RES..1
(-5875 1225);
FORCEPROP 1 LAST LOCATION R841
J 0
(-6175 1225);
DISPLAY 0.978723 (-6175 1225);
PAINT SKYBLUE (-6175 1225);
FORCEPROP 0 LAST $SEC 1
J 0
(-5350 1275);
DISPLAY 0.680851 (-5350 1275);
PAINT MONO (-5350 1275);
DISPLAY INVISIBLE (-5350 1275);
FORCEPROP 0 LAST CDS_SEC 1
J 0
(-5350 1275);
DISPLAY 0.680851 (-5350 1275);
DISPLAY INVISIBLE (-5350 1275);
FORCEPROP 1 LASTPIN (-5975 1225) $PN 1
J 0
(-5963 1237);
DISPLAY 0.787234 (-5963 1237);
PAINT MONO (-5963 1237);
FORCEPROP 1 LASTPIN (-5775 1225) $PN 2
J 0
(-5813 1237);
DISPLAY 0.787234 (-5813 1237);
PAINT MONO (-5813 1237);
FORCEPROP 1 LAST MATERIAL CHIP
J 0
(-5575 1225);
DISPLAY 0.978723 (-5575 1225);
FORCEPROP 1 LAST VALUE 1K
J 2
(-5600 1225);
DISPLAY 0.978723 (-5600 1225);
FORCEPROP 1 LAST PACK_TYPE 0201LF
J 0
(-5350 1225);
DISPLAY 0.978723 (-5350 1225);
FORCEPROP 1 LAST TOLERANCE 1%
J 0
(-5900 1425);
DISPLAY 0.978723 (-5900 1425);
DISPLAY INVISIBLE (-5900 1425);
FORCEPROP 1 LAST WATTAGE 1/20W
J 2
(-5500 1425);
DISPLAY 0.978723 (-5500 1425);
DISPLAY INVISIBLE (-5500 1425);
FORCEPROP 2 LAST CDS_LIB pure_quanta
J 0
(-5875 1225);
DISPLAY INVISIBLE (-5875 1225);
FORCEPROP 1 LAST PATH I17
J 0
(-5925 1375);
DISPLAY 0.978723 (-5925 1375);
PAINT WHITE (-5925 1375);
DISPLAY INVISIBLE (-5925 1375);
FORCEPROP 1 LAST PART_NUMBER CS21001FE07
J 0
(-5925 1325);
DISPLAY 0.978723 (-5925 1325);
DISPLAY INVISIBLE (-5925 1325);
FORCEADD Q_RES..1
(-5725 3375);
FORCEPROP 1 LAST LOCATION R1431
J 0
(-6025 3375);
DISPLAY 0.978723 (-6025 3375);
FORCEPROP 0 LAST $SEC 1
J 0
(-5200 3425);
DISPLAY 0.680851 (-5200 3425);
PAINT MONO (-5200 3425);
DISPLAY INVISIBLE (-5200 3425);
FORCEPROP 0 LAST CDS_SEC 1
J 0
(-5200 3425);
DISPLAY 0.680851 (-5200 3425);
DISPLAY INVISIBLE (-5200 3425);
FORCEPROP 1 LASTPIN (-5825 3375) $PN 1
J 0
(-5813 3387);
DISPLAY 0.787234 (-5813 3387);
PAINT MONO (-5813 3387);
FORCEPROP 1 LASTPIN (-5625 3375) $PN 2
J 0
(-5663 3387);
DISPLAY 0.787234 (-5663 3387);
PAINT MONO (-5663 3387);
FORCEPROP 1 LAST MATERIAL CHIP
J 0
(-5425 3375);
DISPLAY 0.787234 (-5425 3375);
FORCEPROP 1 LAST VALUE 1K
J 2
(-5450 3375);
DISPLAY 0.787234 (-5450 3375);
FORCEPROP 1 LAST PACK_TYPE 0201LF
J 0
(-5200 3375);
DISPLAY 0.787234 (-5200 3375);
FORCEPROP 1 LAST WATTAGE 1/20W
J 2
(-5350 3575);
DISPLAY 0.787234 (-5350 3575);
DISPLAY INVISIBLE (-5350 3575);
FORCEPROP 1 LAST TOLERANCE 1%
J 0
(-5750 3575);
DISPLAY 0.787234 (-5750 3575);
DISPLAY INVISIBLE (-5750 3575);
FORCEPROP 2 LAST CDS_LIB pure_quanta
J 0
(-5725 3375);
DISPLAY INVISIBLE (-5725 3375);
FORCEPROP 1 LAST PATH I170
J 0
(-5775 3525);
DISPLAY 0.978723 (-5775 3525);
PAINT WHITE (-5775 3525);
DISPLAY INVISIBLE (-5775 3525);
FORCEPROP 1 LAST PART_NUMBER CS21001FE07
J 0
(-5775 3475);
DISPLAY 0.787234 (-5775 3475);
DISPLAY INVISIBLE (-5775 3475);
FORCEADD Q_RES..1
(-5725 3325);
FORCEPROP 1 LAST LOCATION R1432
J 0
(-6025 3325);
DISPLAY 0.978723 (-6025 3325);
FORCEPROP 0 LAST $SEC 1
J 0
(-5200 3375);
DISPLAY 0.680851 (-5200 3375);
PAINT MONO (-5200 3375);
DISPLAY INVISIBLE (-5200 3375);
FORCEPROP 0 LAST CDS_SEC 1
J 0
(-5200 3375);
DISPLAY 0.680851 (-5200 3375);
DISPLAY INVISIBLE (-5200 3375);
FORCEPROP 1 LASTPIN (-5825 3325) $PN 1
J 0
(-5813 3337);
DISPLAY 0.787234 (-5813 3337);
PAINT MONO (-5813 3337);
FORCEPROP 1 LASTPIN (-5625 3325) $PN 2
J 0
(-5663 3337);
DISPLAY 0.787234 (-5663 3337);
PAINT MONO (-5663 3337);
FORCEPROP 1 LAST MATERIAL CHIP
J 0
(-5425 3325);
DISPLAY 0.787234 (-5425 3325);
FORCEPROP 1 LAST VALUE 1K
J 2
(-5450 3325);
DISPLAY 0.787234 (-5450 3325);
FORCEPROP 1 LAST PACK_TYPE 0201LF
J 0
(-5200 3325);
DISPLAY 0.787234 (-5200 3325);
FORCEPROP 1 LAST WATTAGE 1/20W
J 2
(-5350 3525);
DISPLAY 0.787234 (-5350 3525);
DISPLAY INVISIBLE (-5350 3525);
FORCEPROP 1 LAST TOLERANCE 1%
J 0
(-5750 3525);
DISPLAY 0.787234 (-5750 3525);
DISPLAY INVISIBLE (-5750 3525);
FORCEPROP 2 LAST CDS_LIB pure_quanta
J 0
(-5725 3325);
DISPLAY INVISIBLE (-5725 3325);
FORCEPROP 1 LAST PATH I171
J 0
(-5775 3475);
DISPLAY 0.978723 (-5775 3475);
PAINT WHITE (-5775 3475);
DISPLAY INVISIBLE (-5775 3475);
FORCEPROP 1 LAST PART_NUMBER CS21001FE07
J 0
(-5775 3425);
DISPLAY 0.787234 (-5775 3425);
DISPLAY INVISIBLE (-5775 3425);
FORCEADD Q_RES..1
(-2575 3600);
FORCEPROP 1 LAST LOCATION R1437
J 0
(-2825 3600);
DISPLAY 0.978723 (-2825 3600);
FORCEPROP 0 LAST $SEC 1
J 0
(-2050 3650);
DISPLAY 0.680851 (-2050 3650);
PAINT MONO (-2050 3650);
DISPLAY INVISIBLE (-2050 3650);
FORCEPROP 0 LAST CDS_SEC 1
J 0
(-2050 3650);
DISPLAY 0.680851 (-2050 3650);
DISPLAY INVISIBLE (-2050 3650);
FORCEPROP 1 LASTPIN (-2675 3600) $PN 1
J 0
(-2663 3612);
DISPLAY 0.787234 (-2663 3612);
PAINT MONO (-2663 3612);
FORCEPROP 1 LASTPIN (-2475 3600) $PN 2
J 0
(-2513 3612);
DISPLAY 0.787234 (-2513 3612);
PAINT MONO (-2513 3612);
FORCEPROP 1 LAST VALUE 1K
J 2
(-2300 3600);
DISPLAY 0.787234 (-2300 3600);
FORCEPROP 1 LAST MATERIAL CHIP
J 0
(-2275 3600);
DISPLAY 0.787234 (-2275 3600);
FORCEPROP 1 LAST PACK_TYPE 0201LF
J 0
(-2050 3600);
DISPLAY 0.787234 (-2050 3600);
FORCEPROP 2 LAST CDS_LIB pure_quanta
J 0
(-2575 3600);
DISPLAY INVISIBLE (-2575 3600);
FORCEPROP 1 LAST WATTAGE 1/20W
J 2
(-2200 3800);
DISPLAY 0.787234 (-2200 3800);
DISPLAY INVISIBLE (-2200 3800);
FORCEPROP 1 LAST TOLERANCE 1%
J 0
(-2600 3800);
DISPLAY 0.787234 (-2600 3800);
DISPLAY INVISIBLE (-2600 3800);
FORCEPROP 1 LAST PATH I172
J 0
(-2625 3750);
DISPLAY 0.978723 (-2625 3750);
PAINT WHITE (-2625 3750);
DISPLAY INVISIBLE (-2625 3750);
FORCEPROP 1 LAST PART_NUMBER CS21001FE07
J 0
(-2625 3700);
DISPLAY 0.787234 (-2625 3700);
DISPLAY INVISIBLE (-2625 3700);
FORCEADD Q_RES..1
(-2575 3650);
FORCEPROP 1 LAST LOCATION R1436
J 0
(-2825 3650);
DISPLAY 0.978723 (-2825 3650);
FORCEPROP 0 LAST $SEC 1
J 0
(-2200 3900);
DISPLAY 0.680851 (-2200 3900);
PAINT MONO (-2200 3900);
DISPLAY INVISIBLE (-2200 3900);
FORCEPROP 0 LAST CDS_SEC 1
J 0
(-2200 3900);
DISPLAY 0.680851 (-2200 3900);
DISPLAY INVISIBLE (-2200 3900);
FORCEPROP 1 LASTPIN (-2675 3650) $PN 1
J 0
(-2663 3662);
DISPLAY 0.787234 (-2663 3662);
PAINT MONO (-2663 3662);
FORCEPROP 1 LASTPIN (-2475 3650) $PN 2
J 0
(-2513 3662);
DISPLAY 0.787234 (-2513 3662);
PAINT MONO (-2513 3662);
FORCEPROP 1 LAST WATTAGE 1/20W
J 2
(-2200 3850);
DISPLAY 0.978723 (-2200 3850);
FORCEPROP 1 LAST TOLERANCE 1%
J 0
(-2600 3850);
DISPLAY 0.978723 (-2600 3850);
FORCEPROP 1 LAST VALUE 1K
J 2
(-2300 3650);
DISPLAY 0.787234 (-2300 3650);
FORCEPROP 1 LAST MATERIAL CHIP
J 0
(-2275 3650);
DISPLAY 0.787234 (-2275 3650);
FORCEPROP 1 LAST PACK_TYPE 0201LF
J 0
(-2050 3650);
DISPLAY 0.787234 (-2050 3650);
FORCEPROP 2 LAST CDS_LIB pure_quanta
J 0
(-2575 3650);
DISPLAY INVISIBLE (-2575 3650);
FORCEPROP 1 LAST PATH I173
J 0
(-2625 3800);
DISPLAY 0.978723 (-2625 3800);
PAINT WHITE (-2625 3800);
DISPLAY INVISIBLE (-2625 3800);
FORCEPROP 1 LAST PART_NUMBER CS21001FE07
J 0
(-2625 3750);
DISPLAY 0.978723 (-2625 3750);
DISPLAY INVISIBLE (-2625 3750);
FORCEADD Q_RES..1
(-2575 3550);
FORCEPROP 1 LAST LOCATION R1448
J 0
(-2825 3550);
DISPLAY 0.978723 (-2825 3550);
FORCEPROP 0 LAST $SEC 1
J 0
(-2050 3600);
DISPLAY 0.680851 (-2050 3600);
PAINT MONO (-2050 3600);
DISPLAY INVISIBLE (-2050 3600);
FORCEPROP 0 LAST CDS_SEC 1
J 0
(-2050 3600);
DISPLAY 0.680851 (-2050 3600);
DISPLAY INVISIBLE (-2050 3600);
FORCEPROP 1 LASTPIN (-2675 3550) $PN 1
J 0
(-2663 3562);
DISPLAY 0.787234 (-2663 3562);
PAINT MONO (-2663 3562);
FORCEPROP 1 LASTPIN (-2475 3550) $PN 2
J 0
(-2513 3562);
DISPLAY 0.787234 (-2513 3562);
PAINT MONO (-2513 3562);
FORCEPROP 1 LAST PACK_TYPE 0201LF
J 0
(-2050 3550);
DISPLAY 0.787234 (-2050 3550);
FORCEPROP 1 LAST MATERIAL CHIP
J 0
(-2275 3550);
DISPLAY 0.787234 (-2275 3550);
FORCEPROP 1 LAST VALUE 1K
J 2
(-2300 3550);
DISPLAY 0.787234 (-2300 3550);
FORCEPROP 2 LAST CDS_LIB pure_quanta
J 0
(-2575 3550);
DISPLAY INVISIBLE (-2575 3550);
FORCEPROP 1 LAST TOLERANCE 1%
J 0
(-2600 3750);
DISPLAY 0.787234 (-2600 3750);
DISPLAY INVISIBLE (-2600 3750);
FORCEPROP 1 LAST WATTAGE 1/20W
J 2
(-2200 3750);
DISPLAY 0.787234 (-2200 3750);
DISPLAY INVISIBLE (-2200 3750);
FORCEPROP 1 LAST PATH I174
J 0
(-2625 3700);
DISPLAY 0.978723 (-2625 3700);
PAINT WHITE (-2625 3700);
DISPLAY INVISIBLE (-2625 3700);
FORCEPROP 1 LAST PART_NUMBER CS21001FE07
J 0
(-2625 3650);
DISPLAY 0.787234 (-2625 3650);
DISPLAY INVISIBLE (-2625 3650);
FORCEADD Q_RES..1
(-2575 3500);
FORCEPROP 1 LAST LOCATION R1451
J 0
(-2825 3500);
DISPLAY 0.978723 (-2825 3500);
FORCEPROP 0 LAST $SEC 1
J 0
(-2050 3550);
DISPLAY 0.680851 (-2050 3550);
PAINT MONO (-2050 3550);
DISPLAY INVISIBLE (-2050 3550);
FORCEPROP 0 LAST CDS_SEC 1
J 0
(-2050 3550);
DISPLAY 0.680851 (-2050 3550);
DISPLAY INVISIBLE (-2050 3550);
FORCEPROP 1 LASTPIN (-2675 3500) $PN 1
J 0
(-2663 3512);
DISPLAY 0.787234 (-2663 3512);
PAINT MONO (-2663 3512);
FORCEPROP 1 LASTPIN (-2475 3500) $PN 2
J 0
(-2513 3512);
DISPLAY 0.787234 (-2513 3512);
PAINT MONO (-2513 3512);
FORCEPROP 1 LAST PACK_TYPE 0201LF
J 0
(-2050 3500);
DISPLAY 0.787234 (-2050 3500);
FORCEPROP 1 LAST MATERIAL CHIP
J 0
(-2275 3500);
DISPLAY 0.787234 (-2275 3500);
FORCEPROP 1 LAST VALUE 1K
J 2
(-2300 3500);
DISPLAY 0.787234 (-2300 3500);
FORCEPROP 2 LAST CDS_LIB pure_quanta
J 0
(-2575 3500);
DISPLAY INVISIBLE (-2575 3500);
FORCEPROP 1 LAST TOLERANCE 1%
J 0
(-2600 3700);
DISPLAY 0.787234 (-2600 3700);
DISPLAY INVISIBLE (-2600 3700);
FORCEPROP 1 LAST WATTAGE 1/20W
J 2
(-2200 3700);
DISPLAY 0.787234 (-2200 3700);
DISPLAY INVISIBLE (-2200 3700);
FORCEPROP 1 LAST PATH I175
J 0
(-2625 3650);
DISPLAY 0.978723 (-2625 3650);
PAINT WHITE (-2625 3650);
DISPLAY INVISIBLE (-2625 3650);
FORCEPROP 1 LAST PART_NUMBER CS21001FE07
J 0
(-2625 3600);
DISPLAY 0.787234 (-2625 3600);
DISPLAY INVISIBLE (-2625 3600);
FORCEADD Q_RES..1
(-2575 3450);
FORCEPROP 1 LAST LOCATION R1462
J 0
(-2825 3450);
DISPLAY 0.978723 (-2825 3450);
FORCEPROP 0 LAST $SEC 1
J 0
(-2050 3500);
DISPLAY 0.680851 (-2050 3500);
PAINT MONO (-2050 3500);
DISPLAY INVISIBLE (-2050 3500);
FORCEPROP 0 LAST CDS_SEC 1
J 0
(-2050 3500);
DISPLAY 0.680851 (-2050 3500);
DISPLAY INVISIBLE (-2050 3500);
FORCEPROP 1 LASTPIN (-2675 3450) $PN 1
J 0
(-2663 3462);
DISPLAY 0.787234 (-2663 3462);
PAINT MONO (-2663 3462);
FORCEPROP 1 LASTPIN (-2475 3450) $PN 2
J 0
(-2513 3462);
DISPLAY 0.787234 (-2513 3462);
PAINT MONO (-2513 3462);
FORCEPROP 1 LAST PACK_TYPE 0201LF
J 0
(-2050 3450);
DISPLAY 0.787234 (-2050 3450);
FORCEPROP 1 LAST MATERIAL CHIP
J 0
(-2275 3450);
DISPLAY 0.787234 (-2275 3450);
FORCEPROP 1 LAST VALUE 1K
J 2
(-2300 3450);
DISPLAY 0.787234 (-2300 3450);
FORCEPROP 2 LAST CDS_LIB pure_quanta
J 0
(-2575 3450);
DISPLAY INVISIBLE (-2575 3450);
FORCEPROP 1 LAST TOLERANCE 1%
J 0
(-2600 3650);
DISPLAY 0.787234 (-2600 3650);
DISPLAY INVISIBLE (-2600 3650);
FORCEPROP 1 LAST WATTAGE 1/20W
J 2
(-2200 3650);
DISPLAY 0.787234 (-2200 3650);
DISPLAY INVISIBLE (-2200 3650);
FORCEPROP 1 LAST PATH I176
J 0
(-2625 3600);
DISPLAY 0.978723 (-2625 3600);
PAINT WHITE (-2625 3600);
DISPLAY INVISIBLE (-2625 3600);
FORCEPROP 1 LAST PART_NUMBER CS21001FE07
J 0
(-2625 3550);
DISPLAY 0.787234 (-2625 3550);
DISPLAY INVISIBLE (-2625 3550);
FORCEADD Q_RES..1
(-2575 3400);
FORCEPROP 1 LAST LOCATION R1463
J 0
(-2825 3400);
DISPLAY 0.978723 (-2825 3400);
FORCEPROP 0 LAST $SEC 1
J 0
(-2050 3450);
DISPLAY 0.680851 (-2050 3450);
PAINT MONO (-2050 3450);
DISPLAY INVISIBLE (-2050 3450);
FORCEPROP 0 LAST CDS_SEC 1
J 0
(-2050 3450);
DISPLAY 0.680851 (-2050 3450);
DISPLAY INVISIBLE (-2050 3450);
FORCEPROP 1 LASTPIN (-2675 3400) $PN 1
J 0
(-2663 3412);
DISPLAY 0.787234 (-2663 3412);
PAINT MONO (-2663 3412);
FORCEPROP 1 LASTPIN (-2475 3400) $PN 2
J 0
(-2513 3412);
DISPLAY 0.787234 (-2513 3412);
PAINT MONO (-2513 3412);
FORCEPROP 1 LAST PACK_TYPE 0201LF
J 0
(-2050 3400);
DISPLAY 0.787234 (-2050 3400);
FORCEPROP 1 LAST MATERIAL CHIP
J 0
(-2275 3400);
DISPLAY 0.787234 (-2275 3400);
FORCEPROP 1 LAST VALUE 1K
J 2
(-2300 3400);
DISPLAY 0.787234 (-2300 3400);
FORCEPROP 2 LAST CDS_LIB pure_quanta
J 0
(-2575 3400);
DISPLAY INVISIBLE (-2575 3400);
FORCEPROP 1 LAST TOLERANCE 1%
J 0
(-2600 3600);
DISPLAY 0.787234 (-2600 3600);
DISPLAY INVISIBLE (-2600 3600);
FORCEPROP 1 LAST WATTAGE 1/20W
J 2
(-2200 3600);
DISPLAY 0.787234 (-2200 3600);
DISPLAY INVISIBLE (-2200 3600);
FORCEPROP 1 LAST PATH I177
J 0
(-2625 3550);
DISPLAY 0.978723 (-2625 3550);
PAINT WHITE (-2625 3550);
DISPLAY INVISIBLE (-2625 3550);
FORCEPROP 1 LAST PART_NUMBER CS21001FE07
J 0
(-2625 3500);
DISPLAY 0.787234 (-2625 3500);
DISPLAY INVISIBLE (-2625 3500);
FORCEADD Q_RES..1
(-2575 3350);
FORCEPROP 1 LAST LOCATION R1468
J 0
(-2825 3350);
DISPLAY 0.978723 (-2825 3350);
FORCEPROP 0 LAST $SEC 1
J 0
(-2050 3400);
DISPLAY 0.680851 (-2050 3400);
PAINT MONO (-2050 3400);
DISPLAY INVISIBLE (-2050 3400);
FORCEPROP 0 LAST CDS_SEC 1
J 0
(-2050 3400);
DISPLAY 0.680851 (-2050 3400);
DISPLAY INVISIBLE (-2050 3400);
FORCEPROP 1 LASTPIN (-2675 3350) $PN 1
J 0
(-2663 3362);
DISPLAY 0.787234 (-2663 3362);
PAINT MONO (-2663 3362);
FORCEPROP 1 LASTPIN (-2475 3350) $PN 2
J 0
(-2513 3362);
DISPLAY 0.787234 (-2513 3362);
PAINT MONO (-2513 3362);
FORCEPROP 1 LAST PACK_TYPE 0201LF
J 0
(-2050 3350);
DISPLAY 0.787234 (-2050 3350);
FORCEPROP 1 LAST MATERIAL CHIP
J 0
(-2275 3350);
DISPLAY 0.787234 (-2275 3350);
FORCEPROP 1 LAST VALUE 1K
J 2
(-2300 3350);
DISPLAY 0.787234 (-2300 3350);
FORCEPROP 2 LAST CDS_LIB pure_quanta
J 0
(-2575 3350);
DISPLAY INVISIBLE (-2575 3350);
FORCEPROP 1 LAST TOLERANCE 1%
J 0
(-2600 3550);
DISPLAY 0.787234 (-2600 3550);
DISPLAY INVISIBLE (-2600 3550);
FORCEPROP 1 LAST WATTAGE 1/20W
J 2
(-2200 3550);
DISPLAY 0.787234 (-2200 3550);
DISPLAY INVISIBLE (-2200 3550);
FORCEPROP 1 LAST PATH I178
J 0
(-2625 3500);
DISPLAY 0.978723 (-2625 3500);
PAINT WHITE (-2625 3500);
DISPLAY INVISIBLE (-2625 3500);
FORCEPROP 1 LAST PART_NUMBER CS21001FE07
J 0
(-2625 3450);
DISPLAY 0.787234 (-2625 3450);
DISPLAY INVISIBLE (-2625 3450);
FORCEADD Q_RES..1
(-2575 3300);
FORCEPROP 1 LAST LOCATION R1469
J 0
(-2825 3300);
DISPLAY 0.978723 (-2825 3300);
FORCEPROP 0 LAST $SEC 1
J 0
(-2050 3350);
DISPLAY 0.680851 (-2050 3350);
PAINT MONO (-2050 3350);
DISPLAY INVISIBLE (-2050 3350);
FORCEPROP 0 LAST CDS_SEC 1
J 0
(-2050 3350);
DISPLAY 0.680851 (-2050 3350);
DISPLAY INVISIBLE (-2050 3350);
FORCEPROP 1 LASTPIN (-2675 3300) $PN 1
J 0
(-2663 3312);
DISPLAY 0.787234 (-2663 3312);
PAINT MONO (-2663 3312);
FORCEPROP 1 LASTPIN (-2475 3300) $PN 2
J 0
(-2513 3312);
DISPLAY 0.787234 (-2513 3312);
PAINT MONO (-2513 3312);
FORCEPROP 1 LAST PACK_TYPE 0201LF
J 0
(-2050 3300);
DISPLAY 0.787234 (-2050 3300);
FORCEPROP 1 LAST MATERIAL CHIP
J 0
(-2275 3300);
DISPLAY 0.787234 (-2275 3300);
FORCEPROP 1 LAST VALUE 1K
J 2
(-2300 3300);
DISPLAY 0.787234 (-2300 3300);
FORCEPROP 2 LAST CDS_LIB pure_quanta
J 0
(-2575 3300);
DISPLAY INVISIBLE (-2575 3300);
FORCEPROP 1 LAST TOLERANCE 1%
J 0
(-2600 3500);
DISPLAY 0.787234 (-2600 3500);
DISPLAY INVISIBLE (-2600 3500);
FORCEPROP 1 LAST WATTAGE 1/20W
J 2
(-2200 3500);
DISPLAY 0.787234 (-2200 3500);
DISPLAY INVISIBLE (-2200 3500);
FORCEPROP 1 LAST PATH I179
J 0
(-2625 3450);
DISPLAY 0.978723 (-2625 3450);
PAINT WHITE (-2625 3450);
DISPLAY INVISIBLE (-2625 3450);
FORCEPROP 1 LAST PART_NUMBER CS21001FE07
J 0
(-2625 3400);
DISPLAY 0.787234 (-2625 3400);
DISPLAY INVISIBLE (-2625 3400);
FORCEADD Q_RES..1
(-5875 1300);
FORCEPROP 1 LAST LOCATION R840
J 0
(-6175 1300);
DISPLAY 0.978723 (-6175 1300);
PAINT SKYBLUE (-6175 1300);
FORCEPROP 0 LAST $SEC 1
J 0
(-5350 1350);
DISPLAY 0.680851 (-5350 1350);
PAINT MONO (-5350 1350);
DISPLAY INVISIBLE (-5350 1350);
FORCEPROP 0 LAST CDS_SEC 1
J 0
(-5350 1350);
DISPLAY 0.680851 (-5350 1350);
DISPLAY INVISIBLE (-5350 1350);
FORCEPROP 1 LASTPIN (-5975 1300) $PN 1
J 0
(-5963 1312);
DISPLAY 0.787234 (-5963 1312);
PAINT MONO (-5963 1312);
FORCEPROP 1 LASTPIN (-5775 1300) $PN 2
J 0
(-5813 1312);
DISPLAY 0.787234 (-5813 1312);
PAINT MONO (-5813 1312);
FORCEPROP 1 LAST MATERIAL CHIP
J 0
(-5575 1300);
DISPLAY 0.978723 (-5575 1300);
FORCEPROP 1 LAST VALUE 1K
J 2
(-5600 1300);
DISPLAY 0.978723 (-5600 1300);
FORCEPROP 1 LAST PACK_TYPE 0201LF
J 0
(-5350 1300);
DISPLAY 0.978723 (-5350 1300);
FORCEPROP 1 LAST WATTAGE 1/20W
J 2
(-5500 1500);
DISPLAY 0.978723 (-5500 1500);
DISPLAY INVISIBLE (-5500 1500);
FORCEPROP 1 LAST TOLERANCE 1%
J 0
(-5900 1500);
DISPLAY 0.978723 (-5900 1500);
DISPLAY INVISIBLE (-5900 1500);
FORCEPROP 2 LAST CDS_LIB pure_quanta
J 0
(-5875 1300);
DISPLAY INVISIBLE (-5875 1300);
FORCEPROP 1 LAST PATH I18
J 0
(-5925 1450);
DISPLAY 0.978723 (-5925 1450);
PAINT WHITE (-5925 1450);
DISPLAY INVISIBLE (-5925 1450);
FORCEPROP 1 LAST PART_NUMBER CS21001FE07
J 0
(-5925 1400);
DISPLAY 0.978723 (-5925 1400);
DISPLAY INVISIBLE (-5925 1400);
FORCEADD Q_RES..1
(-5875 1450);
FORCEPROP 1 LAST LOCATION R838
J 0
(-6175 1450);
DISPLAY 0.978723 (-6175 1450);
PAINT SKYBLUE (-6175 1450);
FORCEPROP 0 LAST $SEC 1
J 0
(-5350 1500);
DISPLAY 0.680851 (-5350 1500);
PAINT MONO (-5350 1500);
DISPLAY INVISIBLE (-5350 1500);
FORCEPROP 0 LAST CDS_SEC 1
J 0
(-5350 1500);
DISPLAY 0.680851 (-5350 1500);
DISPLAY INVISIBLE (-5350 1500);
FORCEPROP 1 LASTPIN (-5975 1450) $PN 1
J 0
(-5963 1462);
DISPLAY 0.787234 (-5963 1462);
PAINT MONO (-5963 1462);
FORCEPROP 1 LASTPIN (-5775 1450) $PN 2
J 0
(-5813 1462);
DISPLAY 0.787234 (-5813 1462);
PAINT MONO (-5813 1462);
FORCEPROP 1 LAST PACK_TYPE 0201LF
J 0
(-5350 1450);
DISPLAY 0.978723 (-5350 1450);
FORCEPROP 1 LAST VALUE 1K
J 2
(-5600 1450);
DISPLAY 0.978723 (-5600 1450);
FORCEPROP 1 LAST MATERIAL CHIP
J 0
(-5575 1450);
DISPLAY 0.978723 (-5575 1450);
FORCEPROP 1 LAST WATTAGE 1/20W
J 2
(-5500 1650);
DISPLAY 0.978723 (-5500 1650);
DISPLAY INVISIBLE (-5500 1650);
FORCEPROP 1 LAST TOLERANCE 1%
J 0
(-5900 1650);
DISPLAY 0.978723 (-5900 1650);
DISPLAY INVISIBLE (-5900 1650);
FORCEPROP 2 LAST CDS_LIB pure_quanta
J 0
(-5875 1450);
DISPLAY INVISIBLE (-5875 1450);
FORCEPROP 1 LAST PATH I19
J 0
(-5925 1600);
DISPLAY 0.978723 (-5925 1600);
PAINT WHITE (-5925 1600);
DISPLAY INVISIBLE (-5925 1600);
FORCEPROP 1 LAST PART_NUMBER CS21001FE07
J 0
(-5925 1550);
DISPLAY 0.978723 (-5925 1550);
DISPLAY INVISIBLE (-5925 1550);
FORCEADD Q_RES..2
(-8525 1300);
FORCEPROP 1 LAST LOCATION R845
J 0
(-8480 1425);
DISPLAY 0.787234 (-8480 1425);
FORCEPROP 0 LAST $SEC 1
J 0
(-8475 1475);
DISPLAY 0.680851 (-8475 1475);
PAINT MONO (-8475 1475);
DISPLAY INVISIBLE (-8475 1475);
FORCEPROP 0 LAST CDS_SEC 1
J 0
(-8475 1475);
DISPLAY 0.680851 (-8475 1475);
DISPLAY INVISIBLE (-8475 1475);
FORCEPROP 1 LASTPIN (-8525 1400) $PN 1
J 0
(-8520 1362);
DISPLAY 0.787234 (-8520 1362);
PAINT MONO (-8520 1362);
FORCEPROP 1 LASTPIN (-8525 1200) $PN 2
J 0
(-8520 1210);
DISPLAY 0.787234 (-8520 1210);
PAINT MONO (-8520 1210);
FORCEPROP 1 LAST PACK_TYPE 0201LF
J 0
(-8485 1125);
DISPLAY 0.787234 (-8485 1125);
FORCEPROP 1 LAST MATERIAL CHIP
J 0
(-8485 1225);
DISPLAY 0.787234 (-8485 1225);
FORCEPROP 1 LAST VALUE 4.7K
J 0
(-8480 1375);
DISPLAY 0.787234 (-8480 1375);
FORCEPROP 1 LAST TOLERANCE 5%
J 0
(-8480 1325);
DISPLAY 0.787234 (-8480 1325);
FORCEPROP 1 LAST WATTAGE 1/20W
J 0
(-8485 1275);
DISPLAY 0.787234 (-8485 1275);
FORCEPROP 2 LAST CDS_LIB pure_quanta
J 0
(-8525 1300);
DISPLAY INVISIBLE (-8525 1300);
FORCEPROP 1 LAST PATH I2
J 0
(-8475 1475);
DISPLAY 0.978723 (-8475 1475);
PAINT WHITE (-8475 1475);
DISPLAY INVISIBLE (-8475 1475);
FORCEPROP 1 LAST PART_NUMBER CS24701JE04
J 0
(-8485 1175);
DISPLAY 0.978723 (-8485 1175);
DISPLAY INVISIBLE (-8485 1175);
FORCEADD Q_RES..1
(-5875 1375);
FORCEPROP 1 LAST LOCATION R839
J 0
(-6175 1375);
DISPLAY 0.978723 (-6175 1375);
PAINT SKYBLUE (-6175 1375);
FORCEPROP 0 LAST $SEC 1
J 0
(-5350 1425);
DISPLAY 0.680851 (-5350 1425);
PAINT MONO (-5350 1425);
DISPLAY INVISIBLE (-5350 1425);
FORCEPROP 0 LAST CDS_SEC 1
J 0
(-5350 1425);
DISPLAY 0.680851 (-5350 1425);
DISPLAY INVISIBLE (-5350 1425);
FORCEPROP 1 LASTPIN (-5975 1375) $PN 1
J 0
(-5963 1387);
DISPLAY 0.787234 (-5963 1387);
PAINT MONO (-5963 1387);
FORCEPROP 1 LASTPIN (-5775 1375) $PN 2
J 0
(-5813 1387);
DISPLAY 0.787234 (-5813 1387);
PAINT MONO (-5813 1387);
FORCEPROP 1 LAST VALUE 1K
J 2
(-5600 1375);
DISPLAY 0.978723 (-5600 1375);
FORCEPROP 1 LAST PACK_TYPE 0201LF
J 0
(-5350 1375);
DISPLAY 0.978723 (-5350 1375);
FORCEPROP 1 LAST MATERIAL CHIP
J 0
(-5575 1375);
DISPLAY 0.978723 (-5575 1375);
FORCEPROP 1 LAST TOLERANCE 1%
J 0
(-5900 1575);
DISPLAY 0.978723 (-5900 1575);
DISPLAY INVISIBLE (-5900 1575);
FORCEPROP 1 LAST WATTAGE 1/20W
J 2
(-5500 1575);
DISPLAY 0.978723 (-5500 1575);
DISPLAY INVISIBLE (-5500 1575);
FORCEPROP 2 LAST CDS_LIB pure_quanta
J 0
(-5875 1375);
DISPLAY INVISIBLE (-5875 1375);
FORCEPROP 1 LAST PATH I20
J 0
(-5925 1525);
DISPLAY 0.978723 (-5925 1525);
PAINT WHITE (-5925 1525);
DISPLAY INVISIBLE (-5925 1525);
FORCEPROP 1 LAST PART_NUMBER CS21001FE07
J 0
(-5925 1475);
DISPLAY 0.978723 (-5925 1475);
DISPLAY INVISIBLE (-5925 1475);
FORCEADD Q_RES..1
(-5875 1550);
FORCEPROP 1 LAST LOCATION R837
J 0
(-6175 1550);
DISPLAY 0.978723 (-6175 1550);
PAINT SKYBLUE (-6175 1550);
FORCEPROP 0 LAST $SEC 1
J 0
(-5350 1600);
DISPLAY 0.680851 (-5350 1600);
PAINT MONO (-5350 1600);
DISPLAY INVISIBLE (-5350 1600);
FORCEPROP 0 LAST CDS_SEC 1
J 0
(-5350 1600);
DISPLAY 0.680851 (-5350 1600);
DISPLAY INVISIBLE (-5350 1600);
FORCEPROP 1 LASTPIN (-5975 1550) $PN 1
J 0
(-5963 1562);
DISPLAY 0.787234 (-5963 1562);
PAINT MONO (-5963 1562);
FORCEPROP 1 LASTPIN (-5775 1550) $PN 2
J 0
(-5813 1562);
DISPLAY 0.787234 (-5813 1562);
PAINT MONO (-5813 1562);
FORCEPROP 1 LAST VALUE 1K
J 2
(-5600 1550);
DISPLAY 0.978723 (-5600 1550);
FORCEPROP 1 LAST MATERIAL CHIP
J 0
(-5575 1550);
DISPLAY 0.978723 (-5575 1550);
FORCEPROP 1 LAST PACK_TYPE 0201LF
J 0
(-5350 1550);
DISPLAY 0.978723 (-5350 1550);
FORCEPROP 2 LAST CDS_LIB pure_quanta
J 0
(-5875 1550);
DISPLAY INVISIBLE (-5875 1550);
FORCEPROP 1 LAST TOLERANCE 1%
J 0
(-5900 1750);
DISPLAY 0.978723 (-5900 1750);
DISPLAY INVISIBLE (-5900 1750);
FORCEPROP 1 LAST WATTAGE 1/20W
J 2
(-5500 1750);
DISPLAY 0.978723 (-5500 1750);
DISPLAY INVISIBLE (-5500 1750);
FORCEPROP 1 LAST PATH I21
J 0
(-5925 1700);
DISPLAY 0.978723 (-5925 1700);
PAINT WHITE (-5925 1700);
DISPLAY INVISIBLE (-5925 1700);
FORCEPROP 1 LAST PART_NUMBER CS21001FE07
J 0
(-5925 1650);
DISPLAY 0.978723 (-5925 1650);
DISPLAY INVISIBLE (-5925 1650);
FORCEADD Q_RES..1
(-5875 1625);
FORCEPROP 1 LAST LOCATION R836
J 0
(-6175 1625);
DISPLAY 0.978723 (-6175 1625);
PAINT SKYBLUE (-6175 1625);
FORCEPROP 0 LAST $SEC 1
J 0
(-5350 1675);
DISPLAY 0.680851 (-5350 1675);
PAINT MONO (-5350 1675);
DISPLAY INVISIBLE (-5350 1675);
FORCEPROP 0 LAST CDS_SEC 1
J 0
(-5350 1675);
DISPLAY 0.680851 (-5350 1675);
DISPLAY INVISIBLE (-5350 1675);
FORCEPROP 1 LASTPIN (-5975 1625) $PN 1
J 0
(-5963 1637);
DISPLAY 0.787234 (-5963 1637);
PAINT MONO (-5963 1637);
FORCEPROP 1 LASTPIN (-5775 1625) $PN 2
J 0
(-5813 1637);
DISPLAY 0.787234 (-5813 1637);
PAINT MONO (-5813 1637);
FORCEPROP 1 LAST MATERIAL CHIP
J 0
(-5575 1625);
DISPLAY 0.978723 (-5575 1625);
FORCEPROP 1 LAST VALUE 1K
J 2
(-5600 1625);
DISPLAY 0.978723 (-5600 1625);
FORCEPROP 1 LAST PACK_TYPE 0201LF
J 0
(-5350 1625);
DISPLAY 0.978723 (-5350 1625);
FORCEPROP 2 LAST CDS_LIB pure_quanta
J 0
(-5875 1625);
DISPLAY INVISIBLE (-5875 1625);
FORCEPROP 1 LAST WATTAGE 1/20W
J 2
(-5500 1825);
DISPLAY 0.978723 (-5500 1825);
DISPLAY INVISIBLE (-5500 1825);
FORCEPROP 1 LAST TOLERANCE 1%
J 0
(-5900 1825);
DISPLAY 0.978723 (-5900 1825);
DISPLAY INVISIBLE (-5900 1825);
FORCEPROP 1 LAST PATH I22
J 0
(-5925 1775);
DISPLAY 0.978723 (-5925 1775);
PAINT WHITE (-5925 1775);
DISPLAY INVISIBLE (-5925 1775);
FORCEPROP 1 LAST PART_NUMBER CS21001FE07
J 0
(-5925 1725);
DISPLAY 0.978723 (-5925 1725);
DISPLAY INVISIBLE (-5925 1725);
FORCEADD Q_RES..1
(-5875 1700);
FORCEPROP 1 LAST LOCATION R835
J 0
(-6175 1700);
DISPLAY 0.978723 (-6175 1700);
PAINT SKYBLUE (-6175 1700);
FORCEPROP 0 LAST $SEC 1
J 0
(-5350 1750);
DISPLAY 0.680851 (-5350 1750);
PAINT MONO (-5350 1750);
DISPLAY INVISIBLE (-5350 1750);
FORCEPROP 0 LAST CDS_SEC 1
J 0
(-5350 1750);
DISPLAY 0.680851 (-5350 1750);
DISPLAY INVISIBLE (-5350 1750);
FORCEPROP 1 LASTPIN (-5975 1700) $PN 1
J 0
(-5963 1712);
DISPLAY 0.787234 (-5963 1712);
PAINT MONO (-5963 1712);
FORCEPROP 1 LASTPIN (-5775 1700) $PN 2
J 0
(-5813 1712);
DISPLAY 0.787234 (-5813 1712);
PAINT MONO (-5813 1712);
FORCEPROP 1 LAST MATERIAL CHIP
J 0
(-5575 1700);
DISPLAY 0.978723 (-5575 1700);
FORCEPROP 1 LAST VALUE 1K
J 2
(-5600 1700);
DISPLAY 0.978723 (-5600 1700);
FORCEPROP 1 LAST PACK_TYPE 0201LF
J 0
(-5350 1700);
DISPLAY 0.978723 (-5350 1700);
FORCEPROP 1 LAST TOLERANCE 1%
J 0
(-5900 1900);
DISPLAY 0.978723 (-5900 1900);
DISPLAY INVISIBLE (-5900 1900);
FORCEPROP 1 LAST WATTAGE 1/20W
J 2
(-5500 1900);
DISPLAY 0.978723 (-5500 1900);
DISPLAY INVISIBLE (-5500 1900);
FORCEPROP 2 LAST CDS_LIB pure_quanta
J 0
(-5875 1700);
DISPLAY INVISIBLE (-5875 1700);
FORCEPROP 1 LAST PATH I23
J 0
(-5925 1850);
DISPLAY 0.978723 (-5925 1850);
PAINT WHITE (-5925 1850);
DISPLAY INVISIBLE (-5925 1850);
FORCEPROP 1 LAST PART_NUMBER CS21001FE07
J 0
(-5925 1800);
DISPLAY 0.978723 (-5925 1800);
DISPLAY INVISIBLE (-5925 1800);
FORCEADD Q_RES..1
(-5875 1800);
FORCEPROP 1 LAST LOCATION R834
J 0
(-6175 1800);
DISPLAY 0.978723 (-6175 1800);
PAINT SKYBLUE (-6175 1800);
FORCEPROP 0 LAST $SEC 1
J 0
(-5500 2050);
DISPLAY 0.680851 (-5500 2050);
PAINT MONO (-5500 2050);
DISPLAY INVISIBLE (-5500 2050);
FORCEPROP 0 LAST CDS_SEC 1
J 0
(-5500 2050);
DISPLAY 0.680851 (-5500 2050);
DISPLAY INVISIBLE (-5500 2050);
FORCEPROP 1 LASTPIN (-5975 1800) $PN 1
J 0
(-5963 1812);
DISPLAY 0.787234 (-5963 1812);
PAINT MONO (-5963 1812);
FORCEPROP 1 LASTPIN (-5775 1800) $PN 2
J 0
(-5813 1812);
DISPLAY 0.787234 (-5813 1812);
PAINT MONO (-5813 1812);
FORCEPROP 1 LAST TOLERANCE 1%
J 0
(-5900 2000);
DISPLAY 0.978723 (-5900 2000);
FORCEPROP 1 LAST MATERIAL CHIP
J 0
(-5575 1800);
DISPLAY 0.978723 (-5575 1800);
FORCEPROP 1 LAST PACK_TYPE 0201LF
J 0
(-5350 1800);
DISPLAY 0.978723 (-5350 1800);
FORCEPROP 1 LAST WATTAGE 1/20W
J 2
(-5500 2000);
DISPLAY 0.978723 (-5500 2000);
FORCEPROP 1 LAST VALUE 1K
J 2
(-5600 1800);
DISPLAY 0.978723 (-5600 1800);
FORCEPROP 2 LAST CDS_LIB pure_quanta
J 0
(-5875 1800);
DISPLAY INVISIBLE (-5875 1800);
FORCEPROP 1 LAST PATH I24
J 0
(-5925 1950);
DISPLAY 0.978723 (-5925 1950);
PAINT WHITE (-5925 1950);
DISPLAY INVISIBLE (-5925 1950);
FORCEPROP 1 LAST PART_NUMBER CS21001FE07
J 0
(-5925 1900);
DISPLAY 0.978723 (-5925 1900);
DISPLAY INVISIBLE (-5925 1900);
FORCEADD OFFPAGE..2
(-4025 1225);
FORCEPROP 2 LAST $XR1 301 
J 0
(-3716 1225);
DISPLAY 0.638298 (-3716 1225);
PAINT MONO (-3716 1225);
FORCEPROP 2 LAST $XR0 186 
J 0
(-3836 1225);
DISPLAY 0.638298 (-3836 1225);
PAINT MONO (-3836 1225);
FORCEPROP 2 LAST CDS_LIB standard
J 0
(-4025 1225);
DISPLAY INVISIBLE (-4025 1225);
FORCEPROP 1 LAST OFFPAGE TRUE
J 0
(-3700 1100);
DISPLAY 0.872340 (-3700 1100);
PAINT GREEN (-3700 1100);
DISPLAY INVISIBLE (-3700 1100);
FORCEPROP 1 LAST COMMENT_BODY TRUE
J 0
(-4070 1130);
DISPLAY 0.872340 (-4070 1130);
PAINT GREEN (-4070 1130);
DISPLAY INVISIBLE (-4070 1130);
FORCEPROP 2 LAST PATH I25
J 0
(-3825 1275);
DISPLAY 0.680851 (-3825 1275);
DISPLAY INVISIBLE (-3825 1275);
FORCEADD OFFPAGE..2
(-4025 1300);
FORCEPROP 2 LAST $XR1 301 
J 0
(-3716 1300);
DISPLAY 0.638298 (-3716 1300);
PAINT MONO (-3716 1300);
FORCEPROP 2 LAST $XR0 186 
J 0
(-3836 1300);
DISPLAY 0.638298 (-3836 1300);
PAINT MONO (-3836 1300);
FORCEPROP 2 LAST CDS_LIB standard
J 0
(-4025 1300);
DISPLAY INVISIBLE (-4025 1300);
FORCEPROP 1 LAST OFFPAGE TRUE
J 0
(-3700 1175);
DISPLAY 0.872340 (-3700 1175);
PAINT GREEN (-3700 1175);
DISPLAY INVISIBLE (-3700 1175);
FORCEPROP 1 LAST COMMENT_BODY TRUE
J 0
(-4070 1205);
DISPLAY 0.872340 (-4070 1205);
PAINT GREEN (-4070 1205);
DISPLAY INVISIBLE (-4070 1205);
FORCEPROP 2 LAST PATH I26
J 0
(-3825 1350);
DISPLAY 0.680851 (-3825 1350);
DISPLAY INVISIBLE (-3825 1350);
FORCEADD OFFPAGE..2
(-4025 1375);
FORCEPROP 2 LAST $XR1 312 
J 0
(-3716 1375);
DISPLAY 0.638298 (-3716 1375);
PAINT MONO (-3716 1375);
FORCEPROP 2 LAST $XR0 186 
J 0
(-3836 1375);
DISPLAY 0.638298 (-3836 1375);
PAINT MONO (-3836 1375);
FORCEPROP 2 LAST CDS_LIB standard
J 0
(-4025 1375);
DISPLAY INVISIBLE (-4025 1375);
FORCEPROP 1 LAST OFFPAGE TRUE
J 0
(-3700 1250);
DISPLAY 0.872340 (-3700 1250);
PAINT GREEN (-3700 1250);
DISPLAY INVISIBLE (-3700 1250);
FORCEPROP 1 LAST COMMENT_BODY TRUE
J 0
(-4070 1280);
DISPLAY 0.872340 (-4070 1280);
PAINT GREEN (-4070 1280);
DISPLAY INVISIBLE (-4070 1280);
FORCEPROP 2 LAST PATH I27
J 0
(-3825 1425);
DISPLAY 0.680851 (-3825 1425);
DISPLAY INVISIBLE (-3825 1425);
FORCEADD OFFPAGE..2
(-4025 1450);
FORCEPROP 2 LAST $XR1 312 
J 0
(-3716 1450);
DISPLAY 0.638298 (-3716 1450);
PAINT MONO (-3716 1450);
FORCEPROP 2 LAST $XR0 186 
J 0
(-3836 1450);
DISPLAY 0.638298 (-3836 1450);
PAINT MONO (-3836 1450);
FORCEPROP 2 LAST CDS_LIB standard
J 0
(-4025 1450);
DISPLAY INVISIBLE (-4025 1450);
FORCEPROP 1 LAST OFFPAGE TRUE
J 0
(-3700 1325);
DISPLAY 0.872340 (-3700 1325);
PAINT GREEN (-3700 1325);
DISPLAY INVISIBLE (-3700 1325);
FORCEPROP 1 LAST COMMENT_BODY TRUE
J 0
(-4070 1355);
DISPLAY 0.872340 (-4070 1355);
PAINT GREEN (-4070 1355);
DISPLAY INVISIBLE (-4070 1355);
FORCEPROP 2 LAST PATH I28
J 0
(-3825 1500);
DISPLAY 0.680851 (-3825 1500);
DISPLAY INVISIBLE (-3825 1500);
FORCEADD OFFPAGE..2
(-4025 1550);
FORCEPROP 2 LAST $XR1 290 
J 0
(-3716 1550);
DISPLAY 0.638298 (-3716 1550);
PAINT MONO (-3716 1550);
FORCEPROP 2 LAST $XR0 186 
J 0
(-3836 1550);
DISPLAY 0.638298 (-3836 1550);
PAINT MONO (-3836 1550);
FORCEPROP 2 LAST CDS_LIB standard
J 0
(-4025 1550);
DISPLAY INVISIBLE (-4025 1550);
FORCEPROP 1 LAST OFFPAGE TRUE
J 0
(-3700 1425);
DISPLAY 0.872340 (-3700 1425);
PAINT GREEN (-3700 1425);
DISPLAY INVISIBLE (-3700 1425);
FORCEPROP 1 LAST COMMENT_BODY TRUE
J 0
(-4070 1455);
DISPLAY 0.872340 (-4070 1455);
PAINT GREEN (-4070 1455);
DISPLAY INVISIBLE (-4070 1455);
FORCEPROP 2 LAST PATH I29
J 0
(-3825 1600);
DISPLAY 0.680851 (-3825 1600);
DISPLAY INVISIBLE (-3825 1600);
FORCEADD Q_RES..2
(-8225 1300);
FORCEPROP 1 LAST LOCATION R846
J 0
(-8180 1425);
DISPLAY 0.787234 (-8180 1425);
FORCEPROP 0 LAST $SEC 1
J 0
(-8175 1475);
DISPLAY 0.680851 (-8175 1475);
PAINT MONO (-8175 1475);
DISPLAY INVISIBLE (-8175 1475);
FORCEPROP 0 LAST CDS_SEC 1
J 0
(-8175 1475);
DISPLAY 0.680851 (-8175 1475);
DISPLAY INVISIBLE (-8175 1475);
FORCEPROP 1 LASTPIN (-8225 1400) $PN 1
J 0
(-8220 1362);
DISPLAY 0.787234 (-8220 1362);
PAINT MONO (-8220 1362);
FORCEPROP 1 LASTPIN (-8225 1200) $PN 2
J 0
(-8220 1210);
DISPLAY 0.787234 (-8220 1210);
PAINT MONO (-8220 1210);
FORCEPROP 1 LAST PACK_TYPE 0201LF
J 0
(-8185 1125);
DISPLAY 0.787234 (-8185 1125);
FORCEPROP 1 LAST MATERIAL CHIP
J 0
(-8185 1225);
DISPLAY 0.787234 (-8185 1225);
FORCEPROP 1 LAST WATTAGE 1/20W
J 0
(-8185 1275);
DISPLAY 0.787234 (-8185 1275);
FORCEPROP 1 LAST TOLERANCE 5%
J 0
(-8180 1325);
DISPLAY 0.787234 (-8180 1325);
FORCEPROP 1 LAST VALUE 4.7K
J 0
(-8180 1375);
DISPLAY 0.787234 (-8180 1375);
FORCEPROP 2 LAST CDS_LIB pure_quanta
J 0
(-8225 1300);
DISPLAY INVISIBLE (-8225 1300);
FORCEPROP 1 LAST PATH I3
J 0
(-8175 1475);
DISPLAY 0.978723 (-8175 1475);
PAINT WHITE (-8175 1475);
DISPLAY INVISIBLE (-8175 1475);
FORCEPROP 1 LAST PART_NUMBER CS24701JE04
J 0
(-8185 1175);
DISPLAY 0.978723 (-8185 1175);
DISPLAY INVISIBLE (-8185 1175);
FORCEADD OFFPAGE..2
(-4025 1625);
FORCEPROP 2 LAST $XR1 290 
J 0
(-3716 1625);
DISPLAY 0.638298 (-3716 1625);
PAINT MONO (-3716 1625);
FORCEPROP 2 LAST $XR0 186 
J 0
(-3836 1625);
DISPLAY 0.638298 (-3836 1625);
PAINT MONO (-3836 1625);
FORCEPROP 2 LAST CDS_LIB standard
J 0
(-4025 1625);
DISPLAY INVISIBLE (-4025 1625);
FORCEPROP 1 LAST OFFPAGE TRUE
J 0
(-3700 1500);
DISPLAY 0.872340 (-3700 1500);
PAINT GREEN (-3700 1500);
DISPLAY INVISIBLE (-3700 1500);
FORCEPROP 1 LAST COMMENT_BODY TRUE
J 0
(-4070 1530);
DISPLAY 0.872340 (-4070 1530);
PAINT GREEN (-4070 1530);
DISPLAY INVISIBLE (-4070 1530);
FORCEPROP 2 LAST PATH I30
J 0
(-3825 1675);
DISPLAY 0.680851 (-3825 1675);
DISPLAY INVISIBLE (-3825 1675);
FORCEADD OFFPAGE..2
(-4025 1700);
FORCEPROP 2 LAST $XR1 279 
J 0
(-3716 1700);
DISPLAY 0.638298 (-3716 1700);
PAINT MONO (-3716 1700);
FORCEPROP 2 LAST $XR0 186 
J 0
(-3836 1700);
DISPLAY 0.638298 (-3836 1700);
PAINT MONO (-3836 1700);
FORCEPROP 2 LAST CDS_LIB standard
J 0
(-4025 1700);
DISPLAY INVISIBLE (-4025 1700);
FORCEPROP 1 LAST OFFPAGE TRUE
J 0
(-3700 1575);
DISPLAY 0.872340 (-3700 1575);
PAINT GREEN (-3700 1575);
DISPLAY INVISIBLE (-3700 1575);
FORCEPROP 1 LAST COMMENT_BODY TRUE
J 0
(-4070 1605);
DISPLAY 0.872340 (-4070 1605);
PAINT GREEN (-4070 1605);
DISPLAY INVISIBLE (-4070 1605);
FORCEPROP 2 LAST PATH I31
J 0
(-3825 1750);
DISPLAY 0.680851 (-3825 1750);
DISPLAY INVISIBLE (-3825 1750);
FORCEADD OFFPAGE..2
(-4025 1800);
FORCEPROP 2 LAST $XR1 279 
J 0
(-3716 1800);
DISPLAY 0.638298 (-3716 1800);
PAINT MONO (-3716 1800);
FORCEPROP 2 LAST $XR0 186 
J 0
(-3836 1800);
DISPLAY 0.638298 (-3836 1800);
PAINT MONO (-3836 1800);
FORCEPROP 2 LAST CDS_LIB standard
J 2
(-4025 1800);
DISPLAY INVISIBLE (-4025 1800);
FORCEPROP 1 LAST OFFPAGE TRUE
J 0
(-3700 1675);
DISPLAY 0.872340 (-3700 1675);
PAINT GREEN (-3700 1675);
DISPLAY INVISIBLE (-3700 1675);
FORCEPROP 1 LAST COMMENT_BODY TRUE
J 0
(-4070 1705);
DISPLAY 0.872340 (-4070 1705);
PAINT GREEN (-4070 1705);
DISPLAY INVISIBLE (-4070 1705);
FORCEPROP 2 LAST PATH I32
J 0
(-3825 1850);
DISPLAY 0.680851 (-3825 1850);
DISPLAY INVISIBLE (-3825 1850);
FORCEADD UNIVERSAL_GND..1
(-4175 4825);
FORCEPROP 3 LASTPIN (-4175 4875) SIG_NAME GND\g
J 0
(-4165 4885);
DISPLAY 0.659574 (-4165 4885);
PAINT MONO (-4165 4885);
DISPLAY INVISIBLE (-4165 4885);
FORCEPROP 2 LAST CDS_LIB pure_quanta_power
J 0
(-4175 4825);
DISPLAY INVISIBLE (-4175 4825);
FORCEPROP 1 LAST HDL_POWER GND
J 1
(-4150 4750);
DISPLAY 0.872340 (-4150 4750);
PAINT GREEN (-4150 4750);
DISPLAY INVISIBLE (-4150 4750);
FORCEPROP 1 LAST PATH I33
J 0
(-4100 4825);
DISPLAY 0.872340 (-4100 4825);
PAINT AQUA (-4100 4825);
DISPLAY INVISIBLE (-4100 4825);
FORCEADD OFFPAGE..2
R 2
(-7950 5100);
FORCEPROP 2 LAST $XR0 186 
J 0
(-8235 5100);
DISPLAY 0.638298 (-8235 5100);
PAINT MONO (-8235 5100);
FORCEPROP 2 LAST CDS_LIB standard
J 0
(-7950 5100);
DISPLAY INVISIBLE (-7950 5100);
FORCEPROP 1 LAST OFFPAGE TRUE
J 2
(-8275 4975);
DISPLAY 0.872340 (-8275 4975);
PAINT GREEN (-8275 4975);
DISPLAY INVISIBLE (-8275 4975);
FORCEPROP 1 LAST COMMENT_BODY TRUE
J 2
(-7905 5005);
DISPLAY 0.872340 (-7905 5005);
PAINT GREEN (-7905 5005);
DISPLAY INVISIBLE (-7905 5005);
FORCEPROP 2 LAST PATH I34
J 0
(-8225 5150);
DISPLAY 0.680851 (-8225 5150);
DISPLAY INVISIBLE (-8225 5150);
FORCEADD OFFPAGE..3
R 2
(-7925 5150);
FORCEPROP 2 LAST $XR0 186 
J 0
(-8235 5150);
DISPLAY 0.638298 (-8235 5150);
PAINT MONO (-8235 5150);
FORCEPROP 2 LAST CDS_LIB standard
J 0
(-7925 5150);
DISPLAY INVISIBLE (-7925 5150);
FORCEPROP 1 LAST OFFPAGE TRUE
J 2
(-8250 5025);
DISPLAY 0.872340 (-8250 5025);
PAINT GREEN (-8250 5025);
DISPLAY INVISIBLE (-8250 5025);
FORCEPROP 1 LAST COMMENT_BODY TRUE
J 2
(-7875 5050);
DISPLAY 0.872340 (-7875 5050);
PAINT GREEN (-7875 5050);
DISPLAY INVISIBLE (-7875 5050);
FORCEPROP 2 LAST PATH I35
J 0
(-8225 5200);
DISPLAY 0.680851 (-8225 5200);
DISPLAY INVISIBLE (-8225 5200);
FORCEADD OFFPAGE..2
R 2
(-7950 5200);
FORCEPROP 2 LAST $XR0 186 
J 0
(-8235 5200);
DISPLAY 0.638298 (-8235 5200);
PAINT MONO (-8235 5200);
FORCEPROP 2 LAST CDS_LIB standard
J 0
(-7950 5200);
DISPLAY INVISIBLE (-7950 5200);
FORCEPROP 1 LAST OFFPAGE TRUE
J 2
(-8275 5075);
DISPLAY 0.872340 (-8275 5075);
PAINT GREEN (-8275 5075);
DISPLAY INVISIBLE (-8275 5075);
FORCEPROP 1 LAST COMMENT_BODY TRUE
J 2
(-7905 5105);
DISPLAY 0.872340 (-7905 5105);
PAINT GREEN (-7905 5105);
DISPLAY INVISIBLE (-7905 5105);
FORCEPROP 2 LAST PATH I36
J 0
(-8225 5250);
DISPLAY 0.680851 (-8225 5250);
DISPLAY INVISIBLE (-8225 5250);
FORCEADD OFFPAGE..3
R 2
(-7925 5250);
FORCEPROP 2 LAST $XR0 186 
J 0
(-8235 5250);
DISPLAY 0.638298 (-8235 5250);
PAINT MONO (-8235 5250);
FORCEPROP 2 LAST CDS_LIB standard
J 0
(-7925 5250);
DISPLAY INVISIBLE (-7925 5250);
FORCEPROP 1 LAST OFFPAGE TRUE
J 2
(-8250 5125);
DISPLAY 0.872340 (-8250 5125);
PAINT GREEN (-8250 5125);
DISPLAY INVISIBLE (-8250 5125);
FORCEPROP 1 LAST COMMENT_BODY TRUE
J 2
(-7875 5150);
DISPLAY 0.872340 (-7875 5150);
PAINT GREEN (-7875 5150);
DISPLAY INVISIBLE (-7875 5150);
FORCEPROP 2 LAST PATH I37
J 0
(-8225 5300);
DISPLAY 0.680851 (-8225 5300);
DISPLAY INVISIBLE (-8225 5300);
FORCEADD OFFPAGE..2
R 2
(-7950 5300);
FORCEPROP 2 LAST $XR0 186 
J 0
(-8235 5300);
DISPLAY 0.638298 (-8235 5300);
PAINT MONO (-8235 5300);
FORCEPROP 2 LAST CDS_LIB standard
J 0
(-7950 5300);
DISPLAY INVISIBLE (-7950 5300);
FORCEPROP 1 LAST OFFPAGE TRUE
J 2
(-8275 5175);
DISPLAY 0.872340 (-8275 5175);
PAINT GREEN (-8275 5175);
DISPLAY INVISIBLE (-8275 5175);
FORCEPROP 1 LAST COMMENT_BODY TRUE
J 2
(-7905 5205);
DISPLAY 0.872340 (-7905 5205);
PAINT GREEN (-7905 5205);
DISPLAY INVISIBLE (-7905 5205);
FORCEPROP 2 LAST PATH I38
J 0
(-8225 5350);
DISPLAY 0.680851 (-8225 5350);
DISPLAY INVISIBLE (-8225 5350);
FORCEADD OFFPAGE..3
R 2
(-7925 5350);
FORCEPROP 2 LAST $XR0 186 
J 0
(-8235 5350);
DISPLAY 0.638298 (-8235 5350);
PAINT MONO (-8235 5350);
FORCEPROP 2 LAST CDS_LIB standard
J 0
(-7925 5350);
DISPLAY INVISIBLE (-7925 5350);
FORCEPROP 1 LAST OFFPAGE TRUE
J 2
(-8250 5225);
DISPLAY 0.872340 (-8250 5225);
PAINT GREEN (-8250 5225);
DISPLAY INVISIBLE (-8250 5225);
FORCEPROP 1 LAST COMMENT_BODY TRUE
J 2
(-7875 5250);
DISPLAY 0.872340 (-7875 5250);
PAINT GREEN (-7875 5250);
DISPLAY INVISIBLE (-7875 5250);
FORCEPROP 2 LAST PATH I39
J 0
(-8225 5400);
DISPLAY 0.680851 (-8225 5400);
DISPLAY INVISIBLE (-8225 5400);
FORCEADD Q_RES..2
(-8525 2075);
FORCEPROP 1 LAST LOCATION R842
J 0
(-8480 2200);
DISPLAY 0.787234 (-8480 2200);
FORCEPROP 0 LAST $SEC 1
J 0
(-8475 2250);
DISPLAY 0.680851 (-8475 2250);
PAINT MONO (-8475 2250);
DISPLAY INVISIBLE (-8475 2250);
FORCEPROP 0 LAST CDS_SEC 1
J 0
(-8475 2250);
DISPLAY 0.680851 (-8475 2250);
DISPLAY INVISIBLE (-8475 2250);
FORCEPROP 1 LASTPIN (-8525 2175) $PN 1
J 0
(-8520 2137);
DISPLAY 0.787234 (-8520 2137);
PAINT MONO (-8520 2137);
FORCEPROP 1 LASTPIN (-8525 1975) $PN 2
J 0
(-8520 1985);
DISPLAY 0.787234 (-8520 1985);
PAINT MONO (-8520 1985);
FORCEPROP 1 LAST MATERIAL EMPTY
J 0
(-8485 2000);
DISPLAY 0.787234 (-8485 2000);
FORCEPROP 1 LAST TOLERANCE 5%
J 0
(-8480 2100);
DISPLAY 0.787234 (-8480 2100);
FORCEPROP 1 LAST VALUE 4.7K
J 0
(-8480 2150);
DISPLAY 0.787234 (-8480 2150);
FORCEPROP 1 LAST WATTAGE 1/20W
J 0
(-8485 2050);
DISPLAY 0.787234 (-8485 2050);
FORCEPROP 1 LAST PACK_TYPE 0201LF
J 0
(-8475 1925);
DISPLAY 0.787234 (-8475 1925);
FORCEPROP 2 LAST CDS_LIB pure_quanta
J 0
(-8525 2075);
DISPLAY INVISIBLE (-8525 2075);
FORCEPROP 1 LAST PATH I4
J 0
(-8475 2250);
DISPLAY 0.978723 (-8475 2250);
PAINT WHITE (-8475 2250);
DISPLAY INVISIBLE (-8475 2250);
FORCEPROP 1 LAST PART_NUMBER CS24701JE04
J 0
(-8485 1950);
DISPLAY 0.978723 (-8485 1950);
DISPLAY INVISIBLE (-8485 1950);
FORCEADD OFFPAGE..2
R 2
(-7950 5400);
FORCEPROP 2 LAST $XR0 186 
J 0
(-8235 5400);
DISPLAY 0.638298 (-8235 5400);
PAINT MONO (-8235 5400);
FORCEPROP 2 LAST CDS_LIB standard
J 2
(-7950 5400);
DISPLAY INVISIBLE (-7950 5400);
FORCEPROP 1 LAST OFFPAGE TRUE
J 2
(-8275 5275);
DISPLAY 0.872340 (-8275 5275);
PAINT GREEN (-8275 5275);
DISPLAY INVISIBLE (-8275 5275);
FORCEPROP 1 LAST COMMENT_BODY TRUE
J 2
(-7905 5305);
DISPLAY 0.872340 (-7905 5305);
PAINT GREEN (-7905 5305);
DISPLAY INVISIBLE (-7905 5305);
FORCEPROP 2 LAST PATH I40
J 0
(-8225 5450);
DISPLAY 0.680851 (-8225 5450);
DISPLAY INVISIBLE (-8225 5450);
FORCEADD OFFPAGE..3
R 2
(-7925 5450);
FORCEPROP 2 LAST $XR0 186 
J 0
(-8235 5450);
DISPLAY 0.638298 (-8235 5450);
PAINT MONO (-8235 5450);
FORCEPROP 2 LAST CDS_LIB standard
J 2
(-7925 5450);
DISPLAY INVISIBLE (-7925 5450);
FORCEPROP 1 LAST OFFPAGE TRUE
J 2
(-8250 5325);
DISPLAY 0.872340 (-8250 5325);
PAINT GREEN (-8250 5325);
DISPLAY INVISIBLE (-8250 5325);
FORCEPROP 1 LAST COMMENT_BODY TRUE
J 2
(-7875 5350);
DISPLAY 0.872340 (-7875 5350);
PAINT GREEN (-7875 5350);
DISPLAY INVISIBLE (-7875 5350);
FORCEPROP 2 LAST PATH I41
J 0
(-8225 5500);
DISPLAY 0.680851 (-8225 5500);
DISPLAY INVISIBLE (-8225 5500);
FORCEADD Q_RES..1
(-6625 5550);
FORCEPROP 1 LAST LOCATION R848
J 0
(-6475 5550);
DISPLAY 0.638298 (-6475 5550);
PAINT SKYBLUE (-6475 5550);
FORCEPROP 0 LAST $SEC 1
J 0
(-6475 5600);
DISPLAY 0.680851 (-6475 5600);
PAINT MONO (-6475 5600);
DISPLAY INVISIBLE (-6475 5600);
FORCEPROP 0 LAST CDS_SEC 1
J 0
(-6475 5600);
DISPLAY 0.680851 (-6475 5600);
DISPLAY INVISIBLE (-6475 5600);
FORCEPROP 1 LASTPIN (-6725 5550) $PN 1
J 0
(-6713 5562);
DISPLAY 0.787234 (-6713 5562);
PAINT MONO (-6713 5562);
FORCEPROP 1 LASTPIN (-6525 5550) $PN 2
J 0
(-6563 5562);
DISPLAY 0.787234 (-6563 5562);
PAINT MONO (-6563 5562);
FORCEPROP 1 LAST VALUE 0
J 2
(-6750 5550);
DISPLAY 0.510638 (-6750 5550);
FORCEPROP 1 LAST MATERIAL CHIP
J 0
(-6975 5550);
DISPLAY 0.510638 (-6975 5550);
FORCEPROP 1 LAST PACK_TYPE 0201LF
J 0
(-7125 5550);
DISPLAY 0.510638 (-7125 5550);
FORCEPROP 1 LAST TOLERANCE 5%
J 0
(-6850 5550);
DISPLAY 0.510638 (-6850 5550);
FORCEPROP 1 LAST WATTAGE 1/20W
J 2
(-6825 5625);
DISPLAY 0.510638 (-6825 5625);
DISPLAY INVISIBLE (-6825 5625);
FORCEPROP 2 LAST CDS_LIB pure_quanta
J 0
(-6625 5550);
DISPLAY INVISIBLE (-6625 5550);
FORCEPROP 1 LAST PATH I42
J 0
(-6675 5700);
DISPLAY 0.978723 (-6675 5700);
PAINT WHITE (-6675 5700);
DISPLAY INVISIBLE (-6675 5700);
FORCEPROP 1 LAST PART_NUMBER CS00001JE10
J 0
(-6675 5675);
DISPLAY 0.510638 (-6675 5675);
DISPLAY INVISIBLE (-6675 5675);
FORCEADD Q_RES..1
(-6425 5200);
FORCEPROP 1 LAST LOCATION R807
J 0
(-6275 5200);
DISPLAY 0.638298 (-6275 5200);
PAINT SKYBLUE (-6275 5200);
FORCEPROP 0 LAST $SEC 1
J 0
(-6275 5250);
DISPLAY 0.680851 (-6275 5250);
PAINT MONO (-6275 5250);
DISPLAY INVISIBLE (-6275 5250);
FORCEPROP 0 LAST CDS_SEC 1
J 0
(-6275 5250);
DISPLAY 0.680851 (-6275 5250);
DISPLAY INVISIBLE (-6275 5250);
FORCEPROP 1 LASTPIN (-6525 5200) $PN 1
J 0
(-6513 5212);
DISPLAY 0.787234 (-6513 5212);
PAINT MONO (-6513 5212);
FORCEPROP 1 LASTPIN (-6325 5200) $PN 2
J 0
(-6363 5212);
DISPLAY 0.787234 (-6363 5212);
PAINT MONO (-6363 5212);
FORCEPROP 1 LAST MATERIAL CHIP
J 0
(-6775 5200);
DISPLAY 0.510638 (-6775 5200);
FORCEPROP 1 LAST VALUE 0
J 2
(-6550 5200);
DISPLAY 0.510638 (-6550 5200);
FORCEPROP 1 LAST TOLERANCE 5%
J 0
(-6650 5200);
DISPLAY 0.510638 (-6650 5200);
FORCEPROP 1 LAST PACK_TYPE 0201LF
J 0
(-6925 5200);
DISPLAY 0.510638 (-6925 5200);
FORCEPROP 1 LAST WATTAGE 1/20W
J 2
(-6625 5275);
DISPLAY 0.510638 (-6625 5275);
DISPLAY INVISIBLE (-6625 5275);
FORCEPROP 2 LAST CDS_LIB pure_quanta
J 0
(-6425 5200);
DISPLAY INVISIBLE (-6425 5200);
FORCEPROP 1 LAST PATH I43
J 0
(-6475 5350);
DISPLAY 0.978723 (-6475 5350);
PAINT WHITE (-6475 5350);
DISPLAY INVISIBLE (-6475 5350);
FORCEPROP 1 LAST PART_NUMBER CS00001JE10
J 0
(-6475 5325);
DISPLAY 0.510638 (-6475 5325);
DISPLAY INVISIBLE (-6475 5325);
FORCEADD Q_RES..1
(-6425 5100);
FORCEPROP 1 LAST LOCATION R809
J 0
(-6275 5100);
DISPLAY 0.638298 (-6275 5100);
PAINT SKYBLUE (-6275 5100);
FORCEPROP 0 LAST $SEC 1
J 0
(-6275 5150);
DISPLAY 0.680851 (-6275 5150);
PAINT MONO (-6275 5150);
DISPLAY INVISIBLE (-6275 5150);
FORCEPROP 0 LAST CDS_SEC 1
J 0
(-6275 5150);
DISPLAY 0.680851 (-6275 5150);
DISPLAY INVISIBLE (-6275 5150);
FORCEPROP 1 LASTPIN (-6525 5100) $PN 1
J 0
(-6513 5112);
DISPLAY 0.787234 (-6513 5112);
PAINT MONO (-6513 5112);
FORCEPROP 1 LASTPIN (-6325 5100) $PN 2
J 0
(-6363 5112);
DISPLAY 0.787234 (-6363 5112);
PAINT MONO (-6363 5112);
FORCEPROP 1 LAST PACK_TYPE 0201LF
J 0
(-6925 5100);
DISPLAY 0.510638 (-6925 5100);
FORCEPROP 1 LAST VALUE 0
J 2
(-6550 5100);
DISPLAY 0.510638 (-6550 5100);
FORCEPROP 1 LAST TOLERANCE 5%
J 0
(-6650 5100);
DISPLAY 0.510638 (-6650 5100);
FORCEPROP 1 LAST MATERIAL CHIP
J 0
(-6775 5100);
DISPLAY 0.510638 (-6775 5100);
FORCEPROP 2 LAST CDS_LIB pure_quanta
J 0
(-6425 5100);
DISPLAY INVISIBLE (-6425 5100);
FORCEPROP 1 LAST WATTAGE 1/20W
J 2
(-6625 5175);
DISPLAY 0.510638 (-6625 5175);
DISPLAY INVISIBLE (-6625 5175);
FORCEPROP 1 LAST PATH I44
J 0
(-6475 5250);
DISPLAY 0.978723 (-6475 5250);
PAINT WHITE (-6475 5250);
DISPLAY INVISIBLE (-6475 5250);
FORCEPROP 1 LAST PART_NUMBER CS00001JE10
J 0
(-6475 5225);
DISPLAY 0.510638 (-6475 5225);
DISPLAY INVISIBLE (-6475 5225);
FORCEADD Q_RES..1
(-6425 5150);
FORCEPROP 1 LAST LOCATION R808
J 0
(-6275 5150);
DISPLAY 0.638298 (-6275 5150);
PAINT SKYBLUE (-6275 5150);
FORCEPROP 0 LAST $SEC 1
J 0
(-6275 5200);
DISPLAY 0.680851 (-6275 5200);
PAINT MONO (-6275 5200);
DISPLAY INVISIBLE (-6275 5200);
FORCEPROP 0 LAST CDS_SEC 1
J 0
(-6275 5200);
DISPLAY 0.680851 (-6275 5200);
DISPLAY INVISIBLE (-6275 5200);
FORCEPROP 1 LASTPIN (-6525 5150) $PN 1
J 0
(-6513 5162);
DISPLAY 0.787234 (-6513 5162);
PAINT MONO (-6513 5162);
FORCEPROP 1 LASTPIN (-6325 5150) $PN 2
J 0
(-6363 5162);
DISPLAY 0.787234 (-6363 5162);
PAINT MONO (-6363 5162);
FORCEPROP 1 LAST MATERIAL CHIP
J 0
(-6775 5150);
DISPLAY 0.510638 (-6775 5150);
FORCEPROP 1 LAST TOLERANCE 5%
J 0
(-6650 5150);
DISPLAY 0.510638 (-6650 5150);
FORCEPROP 1 LAST VALUE 0
J 2
(-6550 5150);
DISPLAY 0.510638 (-6550 5150);
FORCEPROP 1 LAST PACK_TYPE 0201LF
J 0
(-6925 5150);
DISPLAY 0.510638 (-6925 5150);
FORCEPROP 1 LAST WATTAGE 1/20W
J 2
(-6625 5225);
DISPLAY 0.510638 (-6625 5225);
DISPLAY INVISIBLE (-6625 5225);
FORCEPROP 2 LAST CDS_LIB pure_quanta
J 0
(-6425 5150);
DISPLAY INVISIBLE (-6425 5150);
FORCEPROP 1 LAST PATH I45
J 0
(-6475 5300);
DISPLAY 0.978723 (-6475 5300);
PAINT WHITE (-6475 5300);
DISPLAY INVISIBLE (-6475 5300);
FORCEPROP 1 LAST PART_NUMBER CS00001JE10
J 0
(-6475 5275);
DISPLAY 0.510638 (-6475 5275);
DISPLAY INVISIBLE (-6475 5275);
FORCEADD Q_RES..1
(-6425 5300);
FORCEPROP 1 LAST LOCATION R805
J 0
(-6275 5300);
DISPLAY 0.638298 (-6275 5300);
PAINT SKYBLUE (-6275 5300);
FORCEPROP 0 LAST $SEC 1
J 0
(-6275 5350);
DISPLAY 0.680851 (-6275 5350);
PAINT MONO (-6275 5350);
DISPLAY INVISIBLE (-6275 5350);
FORCEPROP 0 LAST CDS_SEC 1
J 0
(-6275 5350);
DISPLAY 0.680851 (-6275 5350);
DISPLAY INVISIBLE (-6275 5350);
FORCEPROP 1 LASTPIN (-6525 5300) $PN 1
J 0
(-6513 5312);
DISPLAY 0.787234 (-6513 5312);
PAINT MONO (-6513 5312);
FORCEPROP 1 LASTPIN (-6325 5300) $PN 2
J 0
(-6363 5312);
DISPLAY 0.787234 (-6363 5312);
PAINT MONO (-6363 5312);
FORCEPROP 1 LAST MATERIAL CHIP
J 0
(-6775 5300);
DISPLAY 0.510638 (-6775 5300);
FORCEPROP 1 LAST VALUE 0
J 2
(-6550 5300);
DISPLAY 0.510638 (-6550 5300);
FORCEPROP 1 LAST TOLERANCE 5%
J 0
(-6650 5300);
DISPLAY 0.510638 (-6650 5300);
FORCEPROP 1 LAST PACK_TYPE 0201LF
J 0
(-6925 5300);
DISPLAY 0.510638 (-6925 5300);
FORCEPROP 1 LAST WATTAGE 1/20W
J 2
(-6625 5375);
DISPLAY 0.510638 (-6625 5375);
DISPLAY INVISIBLE (-6625 5375);
FORCEPROP 2 LAST CDS_LIB pure_quanta
J 0
(-6425 5300);
DISPLAY INVISIBLE (-6425 5300);
FORCEPROP 1 LAST PATH I46
J 0
(-6475 5450);
DISPLAY 0.978723 (-6475 5450);
PAINT WHITE (-6475 5450);
DISPLAY INVISIBLE (-6475 5450);
FORCEPROP 1 LAST PART_NUMBER CS00001JE10
J 0
(-6475 5425);
DISPLAY 0.510638 (-6475 5425);
DISPLAY INVISIBLE (-6475 5425);
FORCEADD Q_RES..1
(-6425 5250);
FORCEPROP 1 LAST LOCATION R806
J 0
(-6275 5250);
DISPLAY 0.638298 (-6275 5250);
PAINT SKYBLUE (-6275 5250);
FORCEPROP 0 LAST $SEC 1
J 0
(-6275 5300);
DISPLAY 0.680851 (-6275 5300);
PAINT MONO (-6275 5300);
DISPLAY INVISIBLE (-6275 5300);
FORCEPROP 0 LAST CDS_SEC 1
J 0
(-6275 5300);
DISPLAY 0.680851 (-6275 5300);
DISPLAY INVISIBLE (-6275 5300);
FORCEPROP 1 LASTPIN (-6525 5250) $PN 1
J 0
(-6513 5262);
DISPLAY 0.787234 (-6513 5262);
PAINT MONO (-6513 5262);
FORCEPROP 1 LASTPIN (-6325 5250) $PN 2
J 0
(-6363 5262);
DISPLAY 0.787234 (-6363 5262);
PAINT MONO (-6363 5262);
FORCEPROP 1 LAST MATERIAL CHIP
J 0
(-6775 5250);
DISPLAY 0.510638 (-6775 5250);
FORCEPROP 1 LAST TOLERANCE 5%
J 0
(-6650 5250);
DISPLAY 0.510638 (-6650 5250);
FORCEPROP 1 LAST VALUE 0
J 2
(-6550 5250);
DISPLAY 0.510638 (-6550 5250);
FORCEPROP 1 LAST PACK_TYPE 0201LF
J 0
(-6925 5250);
DISPLAY 0.510638 (-6925 5250);
FORCEPROP 2 LAST CDS_LIB pure_quanta
J 0
(-6425 5250);
DISPLAY INVISIBLE (-6425 5250);
FORCEPROP 1 LAST WATTAGE 1/20W
J 2
(-6625 5325);
DISPLAY 0.510638 (-6625 5325);
DISPLAY INVISIBLE (-6625 5325);
FORCEPROP 1 LAST PATH I47
J 0
(-6475 5400);
DISPLAY 0.978723 (-6475 5400);
PAINT WHITE (-6475 5400);
DISPLAY INVISIBLE (-6475 5400);
FORCEPROP 1 LAST PART_NUMBER CS00001JE10
J 0
(-6475 5375);
DISPLAY 0.510638 (-6475 5375);
DISPLAY INVISIBLE (-6475 5375);
FORCEADD Q_RES..1
(-6425 5350);
FORCEPROP 1 LAST LOCATION R803
J 0
(-6275 5350);
DISPLAY 0.638298 (-6275 5350);
PAINT SKYBLUE (-6275 5350);
FORCEPROP 0 LAST $SEC 1
J 0
(-6275 5400);
DISPLAY 0.680851 (-6275 5400);
PAINT MONO (-6275 5400);
DISPLAY INVISIBLE (-6275 5400);
FORCEPROP 0 LAST CDS_SEC 1
J 0
(-6275 5400);
DISPLAY 0.680851 (-6275 5400);
DISPLAY INVISIBLE (-6275 5400);
FORCEPROP 1 LASTPIN (-6525 5350) $PN 1
J 0
(-6513 5362);
DISPLAY 0.787234 (-6513 5362);
PAINT MONO (-6513 5362);
FORCEPROP 1 LASTPIN (-6325 5350) $PN 2
J 0
(-6363 5362);
DISPLAY 0.787234 (-6363 5362);
PAINT MONO (-6363 5362);
FORCEPROP 1 LAST MATERIAL CHIP
J 0
(-6775 5350);
DISPLAY 0.510638 (-6775 5350);
FORCEPROP 1 LAST VALUE 0
J 2
(-6550 5350);
DISPLAY 0.510638 (-6550 5350);
FORCEPROP 1 LAST PACK_TYPE 0201LF
J 0
(-6925 5350);
DISPLAY 0.510638 (-6925 5350);
FORCEPROP 1 LAST TOLERANCE 5%
J 0
(-6650 5350);
DISPLAY 0.510638 (-6650 5350);
FORCEPROP 1 LAST WATTAGE 1/20W
J 2
(-6625 5425);
DISPLAY 0.510638 (-6625 5425);
DISPLAY INVISIBLE (-6625 5425);
FORCEPROP 2 LAST CDS_LIB pure_quanta
J 0
(-6425 5350);
DISPLAY INVISIBLE (-6425 5350);
FORCEPROP 1 LAST PATH I48
J 0
(-6475 5500);
DISPLAY 0.978723 (-6475 5500);
PAINT WHITE (-6475 5500);
DISPLAY INVISIBLE (-6475 5500);
FORCEPROP 1 LAST PART_NUMBER CS00001JE10
J 0
(-6475 5475);
DISPLAY 0.510638 (-6475 5475);
DISPLAY INVISIBLE (-6475 5475);
FORCEADD Q_RES..1
(-6425 5450);
FORCEPROP 1 LAST LOCATION R801
J 0
(-6275 5450);
DISPLAY 0.638298 (-6275 5450);
PAINT SKYBLUE (-6275 5450);
FORCEPROP 2 LAST SEC 1
J 0
(-6475 5650);
DISPLAY 0.680851 (-6475 5650);
PAINT MONO (-6475 5650);
DISPLAY INVISIBLE (-6475 5650);
FORCEPROP 1 LASTPIN (-6525 5450) $PN 1
J 0
(-6513 5462);
DISPLAY 0.787234 (-6513 5462);
PAINT MONO (-6513 5462);
FORCEPROP 1 LASTPIN (-6325 5450) $PN 2
J 0
(-6363 5462);
DISPLAY 0.787234 (-6363 5462);
PAINT MONO (-6363 5462);
FORCEPROP 1 LAST PACK_TYPE 0201LF
J 0
(-6925 5450);
DISPLAY 0.510638 (-6925 5450);
FORCEPROP 1 LAST MATERIAL CHIP
J 0
(-6775 5450);
DISPLAY 0.510638 (-6775 5450);
FORCEPROP 1 LAST TOLERANCE 5%
J 0
(-6650 5450);
DISPLAY 0.510638 (-6650 5450);
FORCEPROP 1 LAST VALUE 0
J 2
(-6550 5450);
DISPLAY 0.510638 (-6550 5450);
FORCEPROP 1 LAST WATTAGE 1/20W
J 2
(-6625 5525);
DISPLAY 0.510638 (-6625 5525);
DISPLAY INVISIBLE (-6625 5525);
FORCEPROP 2 LAST SEC_TYPE 0201LF
J 0
(-6475 5650);
DISPLAY 0.680851 (-6475 5650);
DISPLAY INVISIBLE (-6475 5650);
FORCEPROP 2 LAST CDS_LIB pure_quanta
J 0
(-6425 5450);
DISPLAY INVISIBLE (-6425 5450);
FORCEPROP 1 LAST PATH I49
J 0
(-6475 5600);
DISPLAY 0.978723 (-6475 5600);
PAINT WHITE (-6475 5600);
DISPLAY INVISIBLE (-6475 5600);
FORCEPROP 1 LAST PART_NUMBER CS00001JE10
J 0
(-6475 5575);
DISPLAY 0.510638 (-6475 5575);
DISPLAY INVISIBLE (-6475 5575);
FORCEADD Q_RES..2
(-8225 2075);
FORCEPROP 1 LAST LOCATION R843
J 0
(-8180 2200);
DISPLAY 0.787234 (-8180 2200);
FORCEPROP 0 LAST $SEC 1
J 0
(-8175 2250);
DISPLAY 0.680851 (-8175 2250);
PAINT MONO (-8175 2250);
DISPLAY INVISIBLE (-8175 2250);
FORCEPROP 0 LAST CDS_SEC 1
J 0
(-8175 2250);
DISPLAY 0.680851 (-8175 2250);
DISPLAY INVISIBLE (-8175 2250);
FORCEPROP 1 LASTPIN (-8225 2175) $PN 1
J 0
(-8220 2137);
DISPLAY 0.787234 (-8220 2137);
PAINT MONO (-8220 2137);
FORCEPROP 1 LASTPIN (-8225 1975) $PN 2
J 0
(-8220 1985);
DISPLAY 0.787234 (-8220 1985);
PAINT MONO (-8220 1985);
FORCEPROP 1 LAST WATTAGE 1/20W
J 0
(-8185 2050);
DISPLAY 0.787234 (-8185 2050);
FORCEPROP 1 LAST VALUE 4.7K
J 0
(-8180 2150);
DISPLAY 0.787234 (-8180 2150);
FORCEPROP 1 LAST TOLERANCE 5%
J 0
(-8180 2100);
DISPLAY 0.787234 (-8180 2100);
FORCEPROP 1 LAST PACK_TYPE 0201LF
J 0
(-8175 1925);
DISPLAY 0.787234 (-8175 1925);
FORCEPROP 1 LAST MATERIAL EMPTY
J 0
(-8185 2000);
DISPLAY 0.787234 (-8185 2000);
FORCEPROP 2 LAST CDS_LIB pure_quanta
J 0
(-8225 2075);
DISPLAY INVISIBLE (-8225 2075);
FORCEPROP 1 LAST PATH I5
J 0
(-8175 2250);
DISPLAY 0.978723 (-8175 2250);
PAINT WHITE (-8175 2250);
DISPLAY INVISIBLE (-8175 2250);
FORCEPROP 1 LAST PART_NUMBER CS24701JE04
J 0
(-8185 1950);
DISPLAY 0.978723 (-8185 1950);
DISPLAY INVISIBLE (-8185 1950);
FORCEADD Q_RES..1
(-6425 5400);
FORCEPROP 1 LAST LOCATION R802
J 0
(-6275 5400);
DISPLAY 0.638298 (-6275 5400);
PAINT SKYBLUE (-6275 5400);
FORCEPROP 2 LAST SEC 1
J 0
(-6475 5600);
DISPLAY 0.680851 (-6475 5600);
PAINT MONO (-6475 5600);
DISPLAY INVISIBLE (-6475 5600);
FORCEPROP 1 LASTPIN (-6525 5400) $PN 1
J 0
(-6513 5412);
DISPLAY 0.787234 (-6513 5412);
PAINT MONO (-6513 5412);
FORCEPROP 1 LASTPIN (-6325 5400) $PN 2
J 0
(-6363 5412);
DISPLAY 0.787234 (-6363 5412);
PAINT MONO (-6363 5412);
FORCEPROP 1 LAST PACK_TYPE 0201LF
J 0
(-6925 5400);
DISPLAY 0.510638 (-6925 5400);
FORCEPROP 1 LAST MATERIAL CHIP
J 0
(-6775 5400);
DISPLAY 0.510638 (-6775 5400);
FORCEPROP 1 LAST TOLERANCE 5%
J 0
(-6650 5400);
DISPLAY 0.510638 (-6650 5400);
FORCEPROP 1 LAST VALUE 0
J 2
(-6550 5400);
DISPLAY 0.510638 (-6550 5400);
FORCEPROP 1 LAST WATTAGE 1/20W
J 2
(-6625 5475);
DISPLAY 0.510638 (-6625 5475);
DISPLAY INVISIBLE (-6625 5475);
FORCEPROP 2 LAST SEC_TYPE 0201LF
J 0
(-6475 5600);
DISPLAY 0.680851 (-6475 5600);
DISPLAY INVISIBLE (-6475 5600);
FORCEPROP 2 LAST CDS_LIB pure_quanta
J 0
(-6425 5400);
DISPLAY INVISIBLE (-6425 5400);
FORCEPROP 1 LAST PATH I50
J 0
(-6475 5550);
DISPLAY 0.978723 (-6475 5550);
PAINT WHITE (-6475 5550);
DISPLAY INVISIBLE (-6475 5550);
FORCEPROP 1 LAST PART_NUMBER CS00001JE10
J 0
(-6475 5525);
DISPLAY 0.510638 (-6475 5525);
DISPLAY INVISIBLE (-6475 5525);
FORCEADD OFFPAGE..1
(-6175 5650);
FORCEPROP 2 LAST $XR0 185 
J 0
(-6427 5650);
DISPLAY 0.638298 (-6427 5650);
PAINT MONO (-6427 5650);
FORCEPROP 2 LAST CDS_LIB standard
J 0
(-6175 5650);
DISPLAY INVISIBLE (-6175 5650);
FORCEPROP 1 LAST OFFPAGE TRUE
J 0
(-5850 5525);
DISPLAY 1.170213 (-5850 5525);
PAINT GREEN (-5850 5525);
DISPLAY INVISIBLE (-5850 5525);
FORCEPROP 1 LAST COMMENT_BODY TRUE
J 0
(-6050 5550);
DISPLAY 1.170213 (-6050 5550);
PAINT GREEN (-6050 5550);
DISPLAY INVISIBLE (-6050 5550);
FORCEPROP 2 LAST PATH I51
J 0
(-6450 5700);
DISPLAY 0.680851 (-6450 5700);
DISPLAY INVISIBLE (-6450 5700);
FORCEADD OFFPAGE..1
(-6175 5700);
FORCEPROP 2 LAST $XR0 185 
J 0
(-6427 5700);
DISPLAY 0.638298 (-6427 5700);
PAINT MONO (-6427 5700);
FORCEPROP 2 LAST CDS_LIB standard
J 0
(-6175 5700);
DISPLAY INVISIBLE (-6175 5700);
FORCEPROP 1 LAST OFFPAGE TRUE
J 0
(-5850 5575);
DISPLAY 1.170213 (-5850 5575);
PAINT GREEN (-5850 5575);
DISPLAY INVISIBLE (-5850 5575);
FORCEPROP 1 LAST COMMENT_BODY TRUE
J 0
(-6050 5600);
DISPLAY 1.170213 (-6050 5600);
PAINT GREEN (-6050 5600);
DISPLAY INVISIBLE (-6050 5600);
FORCEPROP 2 LAST PATH I52
J 0
(-6450 5750);
DISPLAY 0.680851 (-6450 5750);
DISPLAY INVISIBLE (-6450 5750);
FORCEADD OFFPAGE..1
(-6175 5750);
FORCEPROP 2 LAST $XR0 185 
J 0
(-6427 5750);
DISPLAY 0.638298 (-6427 5750);
PAINT MONO (-6427 5750);
FORCEPROP 2 LAST CDS_LIB standard
J 0
(-6175 5750);
DISPLAY INVISIBLE (-6175 5750);
FORCEPROP 1 LAST OFFPAGE TRUE
J 0
(-5850 5625);
DISPLAY 1.170213 (-5850 5625);
PAINT GREEN (-5850 5625);
DISPLAY INVISIBLE (-5850 5625);
FORCEPROP 1 LAST COMMENT_BODY TRUE
J 0
(-6050 5650);
DISPLAY 1.170213 (-6050 5650);
PAINT GREEN (-6050 5650);
DISPLAY INVISIBLE (-6050 5650);
FORCEPROP 2 LAST PATH I53
J 0
(-6450 5800);
DISPLAY 0.680851 (-6450 5800);
DISPLAY INVISIBLE (-6450 5800);
FORCEADD UNIVERSAL_GND..1
(-5575 5900);
FORCEPROP 3 LASTPIN (-5575 5950) SIG_NAME GND\g
J 0
(-5565 5960);
DISPLAY 0.659574 (-5565 5960);
PAINT MONO (-5565 5960);
DISPLAY INVISIBLE (-5565 5960);
FORCEPROP 2 LAST CDS_LIB pure_quanta_power
J 0
(-5575 5900);
DISPLAY INVISIBLE (-5575 5900);
FORCEPROP 1 LAST HDL_POWER GND
J 1
(-5550 5825);
DISPLAY 0.872340 (-5550 5825);
PAINT GREEN (-5550 5825);
DISPLAY INVISIBLE (-5550 5825);
FORCEPROP 1 LAST PATH I54
J 0
(-5500 5900);
DISPLAY 0.872340 (-5500 5900);
PAINT AQUA (-5500 5900);
DISPLAY INVISIBLE (-5500 5900);
FORCEADD Q_CAP..1
R 2
(-5575 6200);
FORCEPROP 1 LAST LOCATION C365
J 2
(-5625 6300);
DISPLAY 0.638298 (-5625 6300);
FORCEPROP 0 LAST $SEC 1
J 0
(-5625 6350);
DISPLAY 0.680851 (-5625 6350);
PAINT MONO (-5625 6350);
DISPLAY INVISIBLE (-5625 6350);
FORCEPROP 0 LAST CDS_SEC 1
J 0
(-5625 6350);
DISPLAY 0.680851 (-5625 6350);
DISPLAY INVISIBLE (-5625 6350);
FORCEPROP 1 LASTPIN (-5575 6300) $PN 1
J 2
(-5585 6280);
DISPLAY 0.787234 (-5585 6280);
PAINT MONO (-5585 6280);
FORCEPROP 1 LASTPIN (-5575 6100) $PN 2
J 2
(-5585 6080);
DISPLAY 0.787234 (-5585 6080);
PAINT MONO (-5585 6080);
FORCEPROP 1 LAST VALUE 0.1UF
J 2
(-5625 6250);
DISPLAY 0.638298 (-5625 6250);
FORCEPROP 1 LAST MATERIAL X7S
J 2
(-5625 6100);
DISPLAY 0.638298 (-5625 6100);
FORCEPROP 1 LAST PACK_TYPE C0201
J 2
(-5625 6000);
DISPLAY 0.638298 (-5625 6000);
FORCEPROP 1 LAST VOLTAGE 10V
J 2
(-5625 6200);
DISPLAY 0.638298 (-5625 6200);
FORCEPROP 1 LAST TOLERANCE 10%
J 2
(-5625 6150);
DISPLAY 0.638298 (-5625 6150);
FORCEPROP 2 LAST CDS_LIB pure_quanta
J 2
(-5575 6200);
DISPLAY INVISIBLE (-5575 6200);
FORCEPROP 1 LAST PATH I55
J 2
(-5625 6350);
DISPLAY 0.978723 (-5625 6350);
PAINT WHITE (-5625 6350);
DISPLAY INVISIBLE (-5625 6350);
FORCEPROP 1 LAST PART_NUMBER CH4102K6E00
J 2
(-5625 6050);
DISPLAY 0.638298 (-5625 6050);
DISPLAY INVISIBLE (-5625 6050);
FORCEADD P1V0_AUX..1
(-5400 6450);
FORCEPROP 3 LASTPIN (-5400 6400) SIG_NAME P1V8_AUX\g
J 0
(-5390 6410);
DISPLAY 0.659574 (-5390 6410);
PAINT MONO (-5390 6410);
DISPLAY INVISIBLE (-5390 6410);
FORCEPROP 1 LAST HDL_POWER P1V8_AUX
J 1
(-5390 6490);
DISPLAY 0.489362 (-5390 6490);
PAINT GREEN (-5390 6490);
FORCEPROP 2 LAST CDS_LIB pure_quanta_power
J 0
(-5400 6450);
DISPLAY INVISIBLE (-5400 6450);
FORCEPROP 1 LAST PATH I56
J 0
(-5350 6475);
DISPLAY 0.872340 (-5350 6475);
PAINT AQUA (-5350 6475);
DISPLAY INVISIBLE (-5350 6475);
FORCEADD P1V0..1
(-3075 2025);
FORCEPROP 3 LASTPIN (-3075 1975) SIG_NAME P1V8_CPU1_RT_1D\g
J 0
(-3065 1985);
DISPLAY 0.659574 (-3065 1985);
PAINT MONO (-3065 1985);
DISPLAY INVISIBLE (-3065 1985);
FORCEPROP 1 LAST HDL_POWER P1V8_CPU1_RT_1D
J 1
(-3075 2075);
DISPLAY 0.957447 (-3075 2075);
PAINT SKYBLUE (-3075 2075);
FORCEPROP 2 LAST CDS_LIB pure_quanta_power
J 0
(-3075 2025);
DISPLAY INVISIBLE (-3075 2025);
FORCEPROP 1 LAST PATH I57
J 0
(-3025 2050);
DISPLAY 0.872340 (-3025 2050);
PAINT AQUA (-3025 2050);
DISPLAY INVISIBLE (-3025 2050);
FORCEADD Q_RES..1
(-2550 1150);
FORCEPROP 1 LAST LOCATION R827
J 0
(-2850 1150);
DISPLAY 0.978723 (-2850 1150);
PAINT SKYBLUE (-2850 1150);
FORCEPROP 0 LAST $SEC 1
J 0
(-2025 1200);
DISPLAY 0.680851 (-2025 1200);
PAINT MONO (-2025 1200);
DISPLAY INVISIBLE (-2025 1200);
FORCEPROP 0 LAST CDS_SEC 1
J 0
(-2025 1200);
DISPLAY 0.680851 (-2025 1200);
DISPLAY INVISIBLE (-2025 1200);
FORCEPROP 1 LASTPIN (-2650 1150) $PN 1
J 0
(-2638 1162);
DISPLAY 0.787234 (-2638 1162);
PAINT MONO (-2638 1162);
FORCEPROP 1 LASTPIN (-2450 1150) $PN 2
J 0
(-2488 1162);
DISPLAY 0.787234 (-2488 1162);
PAINT MONO (-2488 1162);
FORCEPROP 1 LAST MATERIAL CHIP
J 0
(-2250 1150);
DISPLAY 0.978723 (-2250 1150);
FORCEPROP 1 LAST VALUE 1K
J 2
(-2275 1150);
DISPLAY 0.978723 (-2275 1150);
FORCEPROP 1 LAST PACK_TYPE 0201LF
J 0
(-2025 1150);
DISPLAY 0.978723 (-2025 1150);
FORCEPROP 2 LAST CDS_LIB pure_quanta
J 0
(-2550 1150);
DISPLAY INVISIBLE (-2550 1150);
FORCEPROP 1 LAST WATTAGE 1/20W
J 2
(-2175 1350);
DISPLAY 0.978723 (-2175 1350);
DISPLAY INVISIBLE (-2175 1350);
FORCEPROP 1 LAST TOLERANCE 1%
J 0
(-2575 1350);
DISPLAY 0.978723 (-2575 1350);
DISPLAY INVISIBLE (-2575 1350);
FORCEPROP 1 LAST PATH I58
J 0
(-2600 1300);
DISPLAY 0.978723 (-2600 1300);
PAINT WHITE (-2600 1300);
DISPLAY INVISIBLE (-2600 1300);
FORCEPROP 1 LAST PART_NUMBER CS21001FE07
J 0
(-2600 1250);
DISPLAY 0.978723 (-2600 1250);
DISPLAY INVISIBLE (-2600 1250);
FORCEADD Q_RES..1
(-2550 1225);
FORCEPROP 1 LAST LOCATION R826
J 0
(-2850 1225);
DISPLAY 0.978723 (-2850 1225);
PAINT SKYBLUE (-2850 1225);
FORCEPROP 0 LAST $SEC 1
J 0
(-2025 1275);
DISPLAY 0.680851 (-2025 1275);
PAINT MONO (-2025 1275);
DISPLAY INVISIBLE (-2025 1275);
FORCEPROP 0 LAST CDS_SEC 1
J 0
(-2025 1275);
DISPLAY 0.680851 (-2025 1275);
DISPLAY INVISIBLE (-2025 1275);
FORCEPROP 1 LASTPIN (-2650 1225) $PN 1
J 0
(-2638 1237);
DISPLAY 0.787234 (-2638 1237);
PAINT MONO (-2638 1237);
FORCEPROP 1 LASTPIN (-2450 1225) $PN 2
J 0
(-2488 1237);
DISPLAY 0.787234 (-2488 1237);
PAINT MONO (-2488 1237);
FORCEPROP 1 LAST VALUE 1K
J 2
(-2275 1225);
DISPLAY 0.978723 (-2275 1225);
FORCEPROP 1 LAST MATERIAL CHIP
J 0
(-2250 1225);
DISPLAY 0.978723 (-2250 1225);
FORCEPROP 1 LAST PACK_TYPE 0201LF
J 0
(-2025 1225);
DISPLAY 0.978723 (-2025 1225);
FORCEPROP 2 LAST CDS_LIB pure_quanta
J 0
(-2550 1225);
DISPLAY INVISIBLE (-2550 1225);
FORCEPROP 1 LAST TOLERANCE 1%
J 0
(-2575 1425);
DISPLAY 0.978723 (-2575 1425);
DISPLAY INVISIBLE (-2575 1425);
FORCEPROP 1 LAST WATTAGE 1/20W
J 2
(-2175 1425);
DISPLAY 0.978723 (-2175 1425);
DISPLAY INVISIBLE (-2175 1425);
FORCEPROP 1 LAST PATH I59
J 0
(-2600 1375);
DISPLAY 0.978723 (-2600 1375);
PAINT WHITE (-2600 1375);
DISPLAY INVISIBLE (-2600 1375);
FORCEPROP 1 LAST PART_NUMBER CS21001FE07
J 0
(-2600 1325);
DISPLAY 0.978723 (-2600 1325);
DISPLAY INVISIBLE (-2600 1325);
FORCEADD Q_RES..1
(-2550 1300);
FORCEPROP 1 LAST LOCATION R812
J 0
(-2850 1300);
DISPLAY 0.978723 (-2850 1300);
PAINT SKYBLUE (-2850 1300);
FORCEPROP 0 LAST $SEC 1
J 0
(-2025 1350);
DISPLAY 0.680851 (-2025 1350);
PAINT MONO (-2025 1350);
DISPLAY INVISIBLE (-2025 1350);
FORCEPROP 0 LAST CDS_SEC 1
J 0
(-2025 1350);
DISPLAY 0.680851 (-2025 1350);
DISPLAY INVISIBLE (-2025 1350);
FORCEPROP 1 LASTPIN (-2650 1300) $PN 1
J 0
(-2638 1312);
DISPLAY 0.787234 (-2638 1312);
PAINT MONO (-2638 1312);
FORCEPROP 1 LASTPIN (-2450 1300) $PN 2
J 0
(-2488 1312);
DISPLAY 0.787234 (-2488 1312);
PAINT MONO (-2488 1312);
FORCEPROP 1 LAST VALUE 1K
J 2
(-2275 1300);
DISPLAY 0.978723 (-2275 1300);
FORCEPROP 1 LAST PACK_TYPE 0201LF
J 0
(-2025 1300);
DISPLAY 0.978723 (-2025 1300);
FORCEPROP 1 LAST MATERIAL CHIP
J 0
(-2250 1300);
DISPLAY 0.978723 (-2250 1300);
FORCEPROP 2 LAST CDS_LIB pure_quanta
J 0
(-2550 1300);
DISPLAY INVISIBLE (-2550 1300);
FORCEPROP 1 LAST WATTAGE 1/20W
J 2
(-2175 1500);
DISPLAY 0.978723 (-2175 1500);
DISPLAY INVISIBLE (-2175 1500);
FORCEPROP 1 LAST TOLERANCE 1%
J 0
(-2575 1500);
DISPLAY 0.978723 (-2575 1500);
DISPLAY INVISIBLE (-2575 1500);
FORCEPROP 1 LAST PATH I60
J 0
(-2600 1450);
DISPLAY 0.978723 (-2600 1450);
PAINT WHITE (-2600 1450);
DISPLAY INVISIBLE (-2600 1450);
FORCEPROP 1 LAST PART_NUMBER CS21001FE07
J 0
(-2600 1400);
DISPLAY 0.978723 (-2600 1400);
DISPLAY INVISIBLE (-2600 1400);
FORCEADD Q_RES..1
(-2550 1375);
FORCEPROP 1 LAST LOCATION R810
J 0
(-2850 1375);
DISPLAY 0.978723 (-2850 1375);
PAINT SKYBLUE (-2850 1375);
FORCEPROP 0 LAST $SEC 1
J 0
(-2025 1425);
DISPLAY 0.680851 (-2025 1425);
PAINT MONO (-2025 1425);
DISPLAY INVISIBLE (-2025 1425);
FORCEPROP 0 LAST CDS_SEC 1
J 0
(-2025 1425);
DISPLAY 0.680851 (-2025 1425);
DISPLAY INVISIBLE (-2025 1425);
FORCEPROP 1 LASTPIN (-2650 1375) $PN 1
J 0
(-2638 1387);
DISPLAY 0.787234 (-2638 1387);
PAINT MONO (-2638 1387);
FORCEPROP 1 LASTPIN (-2450 1375) $PN 2
J 0
(-2488 1387);
DISPLAY 0.787234 (-2488 1387);
PAINT MONO (-2488 1387);
FORCEPROP 1 LAST VALUE 1K
J 2
(-2275 1375);
DISPLAY 0.978723 (-2275 1375);
FORCEPROP 1 LAST MATERIAL CHIP
J 0
(-2250 1375);
DISPLAY 0.978723 (-2250 1375);
FORCEPROP 1 LAST PACK_TYPE 0201LF
J 0
(-2025 1375);
DISPLAY 0.978723 (-2025 1375);
FORCEPROP 2 LAST CDS_LIB pure_quanta
J 0
(-2550 1375);
DISPLAY INVISIBLE (-2550 1375);
FORCEPROP 1 LAST TOLERANCE 1%
J 0
(-2575 1575);
DISPLAY 0.978723 (-2575 1575);
DISPLAY INVISIBLE (-2575 1575);
FORCEPROP 1 LAST WATTAGE 1/20W
J 2
(-2175 1575);
DISPLAY 0.978723 (-2175 1575);
DISPLAY INVISIBLE (-2175 1575);
FORCEPROP 1 LAST PATH I61
J 0
(-2600 1525);
DISPLAY 0.978723 (-2600 1525);
PAINT WHITE (-2600 1525);
DISPLAY INVISIBLE (-2600 1525);
FORCEPROP 1 LAST PART_NUMBER CS21001FE07
J 0
(-2600 1475);
DISPLAY 0.978723 (-2600 1475);
DISPLAY INVISIBLE (-2600 1475);
FORCEADD Q_RES..1
(-2550 1475);
FORCEPROP 1 LAST LOCATION R6734
J 0
(-2850 1475);
DISPLAY 0.978723 (-2850 1475);
PAINT SKYBLUE (-2850 1475);
FORCEPROP 0 LAST $SEC 1
J 0
(-2025 1525);
DISPLAY 0.680851 (-2025 1525);
PAINT MONO (-2025 1525);
DISPLAY INVISIBLE (-2025 1525);
FORCEPROP 0 LAST CDS_SEC 1
J 0
(-2025 1525);
DISPLAY 0.680851 (-2025 1525);
DISPLAY INVISIBLE (-2025 1525);
FORCEPROP 1 LASTPIN (-2650 1475) $PN 1
J 0
(-2638 1487);
DISPLAY 0.787234 (-2638 1487);
PAINT MONO (-2638 1487);
FORCEPROP 1 LASTPIN (-2450 1475) $PN 2
J 0
(-2488 1487);
DISPLAY 0.787234 (-2488 1487);
PAINT MONO (-2488 1487);
FORCEPROP 1 LAST VALUE 1K
J 2
(-2275 1475);
DISPLAY 0.978723 (-2275 1475);
FORCEPROP 1 LAST MATERIAL CHIP
J 0
(-2250 1475);
DISPLAY 0.978723 (-2250 1475);
FORCEPROP 1 LAST PACK_TYPE 0201LF
J 0
(-2025 1475);
DISPLAY 0.978723 (-2025 1475);
FORCEPROP 1 LAST WATTAGE 1/20W
J 2
(-2175 1675);
DISPLAY 0.978723 (-2175 1675);
DISPLAY INVISIBLE (-2175 1675);
FORCEPROP 1 LAST TOLERANCE 1%
J 0
(-2575 1675);
DISPLAY 0.978723 (-2575 1675);
DISPLAY INVISIBLE (-2575 1675);
FORCEPROP 2 LAST CDS_LIB pure_quanta
J 0
(-2550 1475);
DISPLAY INVISIBLE (-2550 1475);
FORCEPROP 1 LAST PATH I62
J 0
(-2600 1625);
DISPLAY 0.978723 (-2600 1625);
PAINT WHITE (-2600 1625);
DISPLAY INVISIBLE (-2600 1625);
FORCEPROP 1 LAST PART_NUMBER CS21001FE07
J 0
(-2600 1575);
DISPLAY 0.978723 (-2600 1575);
DISPLAY INVISIBLE (-2600 1575);
FORCEADD Q_RES..1
(-2550 1550);
FORCEPROP 1 LAST LOCATION R6735
J 0
(-2850 1550);
DISPLAY 0.978723 (-2850 1550);
PAINT SKYBLUE (-2850 1550);
FORCEPROP 0 LAST $SEC 1
J 0
(-2025 1600);
DISPLAY 0.680851 (-2025 1600);
PAINT MONO (-2025 1600);
DISPLAY INVISIBLE (-2025 1600);
FORCEPROP 0 LAST CDS_SEC 1
J 0
(-2025 1600);
DISPLAY 0.680851 (-2025 1600);
DISPLAY INVISIBLE (-2025 1600);
FORCEPROP 1 LASTPIN (-2650 1550) $PN 1
J 0
(-2638 1562);
DISPLAY 0.787234 (-2638 1562);
PAINT MONO (-2638 1562);
FORCEPROP 1 LASTPIN (-2450 1550) $PN 2
J 0
(-2488 1562);
DISPLAY 0.787234 (-2488 1562);
PAINT MONO (-2488 1562);
FORCEPROP 1 LAST MATERIAL CHIP
J 0
(-2250 1550);
DISPLAY 0.978723 (-2250 1550);
FORCEPROP 1 LAST PACK_TYPE 0201LF
J 0
(-2025 1550);
DISPLAY 0.978723 (-2025 1550);
FORCEPROP 1 LAST VALUE 1K
J 2
(-2275 1550);
DISPLAY 0.978723 (-2275 1550);
FORCEPROP 1 LAST TOLERANCE 1%
J 0
(-2575 1750);
DISPLAY 0.978723 (-2575 1750);
DISPLAY INVISIBLE (-2575 1750);
FORCEPROP 1 LAST WATTAGE 1/20W
J 2
(-2175 1750);
DISPLAY 0.978723 (-2175 1750);
DISPLAY INVISIBLE (-2175 1750);
FORCEPROP 2 LAST CDS_LIB pure_quanta
J 0
(-2550 1550);
DISPLAY INVISIBLE (-2550 1550);
FORCEPROP 1 LAST PATH I63
J 0
(-2600 1700);
DISPLAY 0.978723 (-2600 1700);
PAINT WHITE (-2600 1700);
DISPLAY INVISIBLE (-2600 1700);
FORCEPROP 1 LAST PART_NUMBER CS21001FE07
J 0
(-2600 1650);
DISPLAY 0.978723 (-2600 1650);
DISPLAY INVISIBLE (-2600 1650);
FORCEADD Q_RES..1
(-2550 1725);
FORCEPROP 1 LAST LOCATION R6707
J 0
(-2850 1725);
DISPLAY 0.978723 (-2850 1725);
PAINT SKYBLUE (-2850 1725);
FORCEPROP 0 LAST $SEC 1
J 0
(-2175 1975);
DISPLAY 0.680851 (-2175 1975);
PAINT MONO (-2175 1975);
DISPLAY INVISIBLE (-2175 1975);
FORCEPROP 0 LAST CDS_SEC 1
J 0
(-2175 1975);
DISPLAY 0.680851 (-2175 1975);
DISPLAY INVISIBLE (-2175 1975);
FORCEPROP 1 LASTPIN (-2650 1725) $PN 1
J 0
(-2638 1737);
DISPLAY 0.787234 (-2638 1737);
PAINT MONO (-2638 1737);
FORCEPROP 1 LASTPIN (-2450 1725) $PN 2
J 0
(-2488 1737);
DISPLAY 0.787234 (-2488 1737);
PAINT MONO (-2488 1737);
FORCEPROP 1 LAST VALUE 1K
J 2
(-2275 1725);
DISPLAY 0.978723 (-2275 1725);
FORCEPROP 1 LAST WATTAGE 1/20W
J 2
(-2175 1925);
DISPLAY 0.978723 (-2175 1925);
FORCEPROP 1 LAST TOLERANCE 1%
J 0
(-2575 1925);
DISPLAY 0.978723 (-2575 1925);
FORCEPROP 1 LAST PACK_TYPE 0201LF
J 0
(-2025 1725);
DISPLAY 0.978723 (-2025 1725);
FORCEPROP 1 LAST MATERIAL CHIP
J 0
(-2250 1725);
DISPLAY 0.978723 (-2250 1725);
FORCEPROP 2 LAST CDS_LIB pure_quanta
J 0
(-2550 1725);
DISPLAY INVISIBLE (-2550 1725);
FORCEPROP 1 LAST PATH I64
J 0
(-2600 1875);
DISPLAY 0.978723 (-2600 1875);
PAINT WHITE (-2600 1875);
DISPLAY INVISIBLE (-2600 1875);
FORCEPROP 1 LAST PART_NUMBER CS21001FE07
J 0
(-2600 1825);
DISPLAY 0.978723 (-2600 1825);
DISPLAY INVISIBLE (-2600 1825);
FORCEADD Q_RES..1
(-2550 1625);
FORCEPROP 1 LAST LOCATION R6706
J 0
(-2850 1625);
DISPLAY 0.978723 (-2850 1625);
PAINT SKYBLUE (-2850 1625);
FORCEPROP 0 LAST $SEC 1
J 0
(-2025 1675);
DISPLAY 0.680851 (-2025 1675);
PAINT MONO (-2025 1675);
DISPLAY INVISIBLE (-2025 1675);
FORCEPROP 0 LAST CDS_SEC 1
J 0
(-2025 1675);
DISPLAY 0.680851 (-2025 1675);
DISPLAY INVISIBLE (-2025 1675);
FORCEPROP 1 LASTPIN (-2650 1625) $PN 1
J 0
(-2638 1637);
DISPLAY 0.787234 (-2638 1637);
PAINT MONO (-2638 1637);
FORCEPROP 1 LASTPIN (-2450 1625) $PN 2
J 0
(-2488 1637);
DISPLAY 0.787234 (-2488 1637);
PAINT MONO (-2488 1637);
FORCEPROP 1 LAST MATERIAL CHIP
J 0
(-2250 1625);
DISPLAY 0.978723 (-2250 1625);
FORCEPROP 1 LAST PACK_TYPE 0201LF
J 0
(-2025 1625);
DISPLAY 0.978723 (-2025 1625);
FORCEPROP 1 LAST VALUE 1K
J 2
(-2275 1625);
DISPLAY 0.978723 (-2275 1625);
FORCEPROP 2 LAST CDS_LIB pure_quanta
J 0
(-2550 1625);
DISPLAY INVISIBLE (-2550 1625);
FORCEPROP 1 LAST WATTAGE 1/20W
J 2
(-2175 1825);
DISPLAY 0.978723 (-2175 1825);
DISPLAY INVISIBLE (-2175 1825);
FORCEPROP 1 LAST TOLERANCE 1%
J 0
(-2575 1825);
DISPLAY 0.978723 (-2575 1825);
DISPLAY INVISIBLE (-2575 1825);
FORCEPROP 1 LAST PATH I65
J 0
(-2600 1775);
DISPLAY 0.978723 (-2600 1775);
PAINT WHITE (-2600 1775);
DISPLAY INVISIBLE (-2600 1775);
FORCEPROP 1 LAST PART_NUMBER CS21001FE07
J 0
(-2600 1725);
DISPLAY 0.978723 (-2600 1725);
DISPLAY INVISIBLE (-2600 1725);
FORCEADD OFFPAGE..2
(-700 1150);
FORCEPROP 2 LAST $XR1 345 
J 0
(-391 1150);
DISPLAY 0.638298 (-391 1150);
PAINT MONO (-391 1150);
FORCEPROP 2 LAST $XR0 186 
J 0
(-511 1150);
DISPLAY 0.638298 (-511 1150);
PAINT MONO (-511 1150);
FORCEPROP 2 LAST CDS_LIB standard
J 0
(-700 1150);
DISPLAY INVISIBLE (-700 1150);
FORCEPROP 1 LAST OFFPAGE TRUE
J 0
(-375 1025);
DISPLAY 0.872340 (-375 1025);
PAINT GREEN (-375 1025);
DISPLAY INVISIBLE (-375 1025);
FORCEPROP 1 LAST COMMENT_BODY TRUE
J 0
(-745 1055);
DISPLAY 0.872340 (-745 1055);
PAINT GREEN (-745 1055);
DISPLAY INVISIBLE (-745 1055);
FORCEPROP 2 LAST PATH I66
J 0
(-500 1200);
DISPLAY 0.680851 (-500 1200);
DISPLAY INVISIBLE (-500 1200);
FORCEADD OFFPAGE..2
(-700 1225);
FORCEPROP 2 LAST $XR1 345 
J 0
(-391 1225);
DISPLAY 0.638298 (-391 1225);
PAINT MONO (-391 1225);
FORCEPROP 2 LAST $XR0 186 
J 0
(-511 1225);
DISPLAY 0.638298 (-511 1225);
PAINT MONO (-511 1225);
FORCEPROP 2 LAST CDS_LIB standard
J 0
(-700 1225);
DISPLAY INVISIBLE (-700 1225);
FORCEPROP 1 LAST OFFPAGE TRUE
J 0
(-375 1100);
DISPLAY 0.872340 (-375 1100);
PAINT GREEN (-375 1100);
DISPLAY INVISIBLE (-375 1100);
FORCEPROP 1 LAST COMMENT_BODY TRUE
J 0
(-745 1130);
DISPLAY 0.872340 (-745 1130);
PAINT GREEN (-745 1130);
DISPLAY INVISIBLE (-745 1130);
FORCEPROP 2 LAST PATH I67
J 0
(-500 1275);
DISPLAY 0.680851 (-500 1275);
DISPLAY INVISIBLE (-500 1275);
FORCEADD OFFPAGE..2
(-700 1300);
FORCEPROP 2 LAST $XR1 356 
J 0
(-391 1300);
DISPLAY 0.638298 (-391 1300);
PAINT MONO (-391 1300);
FORCEPROP 2 LAST $XR0 186 
J 0
(-511 1300);
DISPLAY 0.638298 (-511 1300);
PAINT MONO (-511 1300);
FORCEPROP 2 LAST CDS_LIB standard
J 0
(-700 1300);
DISPLAY INVISIBLE (-700 1300);
FORCEPROP 1 LAST OFFPAGE TRUE
J 0
(-375 1175);
DISPLAY 0.872340 (-375 1175);
PAINT GREEN (-375 1175);
DISPLAY INVISIBLE (-375 1175);
FORCEPROP 1 LAST COMMENT_BODY TRUE
J 0
(-745 1205);
DISPLAY 0.872340 (-745 1205);
PAINT GREEN (-745 1205);
DISPLAY INVISIBLE (-745 1205);
FORCEPROP 2 LAST PATH I68
J 0
(-500 1350);
DISPLAY 0.680851 (-500 1350);
DISPLAY INVISIBLE (-500 1350);
FORCEADD OFFPAGE..2
(-700 1475);
FORCEPROP 2 LAST $XR1 334 
J 0
(-391 1475);
DISPLAY 0.638298 (-391 1475);
PAINT MONO (-391 1475);
FORCEPROP 2 LAST $XR0 186 
J 0
(-511 1475);
DISPLAY 0.638298 (-511 1475);
PAINT MONO (-511 1475);
FORCEPROP 2 LAST CDS_LIB standard
J 0
(-700 1475);
DISPLAY INVISIBLE (-700 1475);
FORCEPROP 1 LAST OFFPAGE TRUE
J 0
(-375 1350);
DISPLAY 0.872340 (-375 1350);
PAINT GREEN (-375 1350);
DISPLAY INVISIBLE (-375 1350);
FORCEPROP 1 LAST COMMENT_BODY TRUE
J 0
(-745 1380);
DISPLAY 0.872340 (-745 1380);
PAINT GREEN (-745 1380);
DISPLAY INVISIBLE (-745 1380);
FORCEPROP 2 LAST PATH I69
J 0
(-375 1525);
DISPLAY 0.680851 (-375 1525);
DISPLAY INVISIBLE (-375 1525);
FORCEADD OFFPAGE..1
(-8125 5550);
FORCEPROP 2 LAST $XR2 186 
J 0
(-8616 5550);
DISPLAY 0.638298 (-8616 5550);
PAINT MONO (-8616 5550);
FORCEPROP 2 LAST $XR1 185 
J 0
(-8496 5550);
DISPLAY 0.638298 (-8496 5550);
PAINT MONO (-8496 5550);
FORCEPROP 2 LAST $XR0 81 
J 0
(-8376 5550);
DISPLAY 0.638298 (-8376 5550);
PAINT MONO (-8376 5550);
FORCEPROP 2 LAST CDS_LIB standard
J 0
(-8125 5550);
DISPLAY INVISIBLE (-8125 5550);
FORCEPROP 1 LAST OFFPAGE TRUE
J 0
(-7800 5425);
DISPLAY 1.170213 (-7800 5425);
PAINT GREEN (-7800 5425);
DISPLAY INVISIBLE (-7800 5425);
FORCEPROP 1 LAST COMMENT_BODY TRUE
J 0
(-8000 5450);
DISPLAY 1.170213 (-8000 5450);
PAINT GREEN (-8000 5450);
DISPLAY INVISIBLE (-8000 5450);
FORCEPROP 2 LAST PATH I7
J 0
(-8325 5600);
DISPLAY 0.680851 (-8325 5600);
DISPLAY INVISIBLE (-8325 5600);
FORCEADD OFFPAGE..2
(-700 1550);
FORCEPROP 2 LAST $XR1 334 
J 0
(-391 1550);
DISPLAY 0.638298 (-391 1550);
PAINT MONO (-391 1550);
FORCEPROP 2 LAST $XR0 186 
J 0
(-511 1550);
DISPLAY 0.638298 (-511 1550);
PAINT MONO (-511 1550);
FORCEPROP 2 LAST CDS_LIB standard
J 0
(-700 1550);
DISPLAY INVISIBLE (-700 1550);
FORCEPROP 1 LAST OFFPAGE TRUE
J 0
(-375 1425);
DISPLAY 0.872340 (-375 1425);
PAINT GREEN (-375 1425);
DISPLAY INVISIBLE (-375 1425);
FORCEPROP 1 LAST COMMENT_BODY TRUE
J 0
(-745 1455);
DISPLAY 0.872340 (-745 1455);
PAINT GREEN (-745 1455);
DISPLAY INVISIBLE (-745 1455);
FORCEPROP 2 LAST PATH I70
J 0
(-375 1600);
DISPLAY 0.680851 (-375 1600);
DISPLAY INVISIBLE (-375 1600);
FORCEADD OFFPAGE..2
(-700 1625);
FORCEPROP 2 LAST $XR1 323 
J 0
(-391 1625);
DISPLAY 0.638298 (-391 1625);
PAINT MONO (-391 1625);
FORCEPROP 2 LAST $XR0 186 
J 0
(-511 1625);
DISPLAY 0.638298 (-511 1625);
PAINT MONO (-511 1625);
FORCEPROP 2 LAST CDS_LIB standard
J 0
(-700 1625);
DISPLAY INVISIBLE (-700 1625);
FORCEPROP 1 LAST OFFPAGE TRUE
J 0
(-375 1500);
DISPLAY 0.872340 (-375 1500);
PAINT GREEN (-375 1500);
DISPLAY INVISIBLE (-375 1500);
FORCEPROP 1 LAST COMMENT_BODY TRUE
J 0
(-745 1530);
DISPLAY 0.872340 (-745 1530);
PAINT GREEN (-745 1530);
DISPLAY INVISIBLE (-745 1530);
FORCEPROP 2 LAST PATH I71
J 0
(-375 1675);
DISPLAY 0.680851 (-375 1675);
DISPLAY INVISIBLE (-375 1675);
FORCEADD OFFPAGE..2
(-700 1725);
FORCEPROP 2 LAST $XR1 323 
J 0
(-391 1725);
DISPLAY 0.638298 (-391 1725);
PAINT MONO (-391 1725);
FORCEPROP 2 LAST $XR0 186 
J 0
(-511 1725);
DISPLAY 0.638298 (-511 1725);
PAINT MONO (-511 1725);
FORCEPROP 2 LAST CDS_LIB standard
J 2
(-700 1725);
DISPLAY INVISIBLE (-700 1725);
FORCEPROP 1 LAST OFFPAGE TRUE
J 0
(-375 1600);
DISPLAY 0.872340 (-375 1600);
PAINT GREEN (-375 1600);
DISPLAY INVISIBLE (-375 1600);
FORCEPROP 1 LAST COMMENT_BODY TRUE
J 0
(-745 1630);
DISPLAY 0.872340 (-745 1630);
PAINT GREEN (-745 1630);
DISPLAY INVISIBLE (-745 1630);
FORCEPROP 2 LAST PATH I72
J 0
(-375 1775);
DISPLAY 0.680851 (-375 1775);
DISPLAY INVISIBLE (-375 1775);
FORCEADD Q_RES..1
(-2775 5100);
FORCEPROP 1 LAST LOCATION R833
J 0
(-2625 5100);
DISPLAY 0.638298 (-2625 5100);
FORCEPROP 0 LAST $SEC 1
J 0
(-2625 5150);
DISPLAY 0.680851 (-2625 5150);
PAINT MONO (-2625 5150);
DISPLAY INVISIBLE (-2625 5150);
FORCEPROP 0 LAST CDS_SEC 1
J 0
(-2625 5150);
DISPLAY 0.680851 (-2625 5150);
DISPLAY INVISIBLE (-2625 5150);
FORCEPROP 1 LASTPIN (-2875 5100) $PN 1
J 0
(-2863 5112);
DISPLAY 0.787234 (-2863 5112);
PAINT MONO (-2863 5112);
FORCEPROP 1 LASTPIN (-2675 5100) $PN 2
J 0
(-2713 5112);
DISPLAY 0.787234 (-2713 5112);
PAINT MONO (-2713 5112);
FORCEPROP 1 LAST TOLERANCE 5%
J 0
(-3000 5100);
DISPLAY 0.510638 (-3000 5100);
FORCEPROP 1 LAST VALUE 0
J 2
(-2900 5100);
DISPLAY 0.510638 (-2900 5100);
FORCEPROP 1 LAST MATERIAL CHIP
J 0
(-3125 5100);
DISPLAY 0.510638 (-3125 5100);
FORCEPROP 1 LAST PACK_TYPE 0201LF
J 0
(-3275 5100);
DISPLAY 0.510638 (-3275 5100);
FORCEPROP 1 LAST WATTAGE 1/20W
J 2
(-2975 5175);
DISPLAY 0.510638 (-2975 5175);
DISPLAY INVISIBLE (-2975 5175);
FORCEPROP 2 LAST CDS_LIB pure_quanta
J 0
(-2775 5100);
DISPLAY INVISIBLE (-2775 5100);
FORCEPROP 1 LAST PATH I73
J 0
(-2825 5250);
DISPLAY 0.978723 (-2825 5250);
PAINT WHITE (-2825 5250);
DISPLAY INVISIBLE (-2825 5250);
FORCEPROP 1 LAST PART_NUMBER CS00001JE10
J 0
(-2825 5225);
DISPLAY 0.510638 (-2825 5225);
DISPLAY INVISIBLE (-2825 5225);
FORCEADD Q_RES..1
(-2775 5200);
FORCEPROP 1 LAST LOCATION R831
J 0
(-2625 5200);
DISPLAY 0.638298 (-2625 5200);
FORCEPROP 0 LAST $SEC 1
J 0
(-2625 5250);
DISPLAY 0.680851 (-2625 5250);
PAINT MONO (-2625 5250);
DISPLAY INVISIBLE (-2625 5250);
FORCEPROP 0 LAST CDS_SEC 1
J 0
(-2625 5250);
DISPLAY 0.680851 (-2625 5250);
DISPLAY INVISIBLE (-2625 5250);
FORCEPROP 1 LASTPIN (-2875 5200) $PN 1
J 0
(-2863 5212);
DISPLAY 0.787234 (-2863 5212);
PAINT MONO (-2863 5212);
FORCEPROP 1 LASTPIN (-2675 5200) $PN 2
J 0
(-2713 5212);
DISPLAY 0.787234 (-2713 5212);
PAINT MONO (-2713 5212);
FORCEPROP 1 LAST MATERIAL CHIP
J 0
(-3125 5200);
DISPLAY 0.510638 (-3125 5200);
FORCEPROP 1 LAST VALUE 0
J 2
(-2900 5200);
DISPLAY 0.510638 (-2900 5200);
FORCEPROP 1 LAST TOLERANCE 5%
J 0
(-3000 5200);
DISPLAY 0.510638 (-3000 5200);
FORCEPROP 1 LAST PACK_TYPE 0201LF
J 0
(-3275 5200);
DISPLAY 0.510638 (-3275 5200);
FORCEPROP 2 LAST CDS_LIB pure_quanta
J 0
(-2775 5200);
DISPLAY INVISIBLE (-2775 5200);
FORCEPROP 1 LAST WATTAGE 1/20W
J 2
(-2975 5275);
DISPLAY 0.510638 (-2975 5275);
DISPLAY INVISIBLE (-2975 5275);
FORCEPROP 1 LAST PATH I74
J 0
(-2825 5350);
DISPLAY 0.978723 (-2825 5350);
PAINT WHITE (-2825 5350);
DISPLAY INVISIBLE (-2825 5350);
FORCEPROP 1 LAST PART_NUMBER CS00001JE10
J 0
(-2825 5325);
DISPLAY 0.510638 (-2825 5325);
DISPLAY INVISIBLE (-2825 5325);
FORCEADD Q_RES..1
(-2775 5150);
FORCEPROP 1 LAST LOCATION R832
J 0
(-2625 5150);
DISPLAY 0.638298 (-2625 5150);
FORCEPROP 0 LAST $SEC 1
J 0
(-2625 5200);
DISPLAY 0.680851 (-2625 5200);
PAINT MONO (-2625 5200);
DISPLAY INVISIBLE (-2625 5200);
FORCEPROP 0 LAST CDS_SEC 1
J 0
(-2625 5200);
DISPLAY 0.680851 (-2625 5200);
DISPLAY INVISIBLE (-2625 5200);
FORCEPROP 1 LASTPIN (-2875 5150) $PN 1
J 0
(-2863 5162);
DISPLAY 0.787234 (-2863 5162);
PAINT MONO (-2863 5162);
FORCEPROP 1 LASTPIN (-2675 5150) $PN 2
J 0
(-2713 5162);
DISPLAY 0.787234 (-2713 5162);
PAINT MONO (-2713 5162);
FORCEPROP 1 LAST VALUE 0
J 2
(-2900 5150);
DISPLAY 0.510638 (-2900 5150);
FORCEPROP 1 LAST MATERIAL CHIP
J 0
(-3125 5150);
DISPLAY 0.510638 (-3125 5150);
FORCEPROP 1 LAST TOLERANCE 5%
J 0
(-3000 5150);
DISPLAY 0.510638 (-3000 5150);
FORCEPROP 1 LAST PACK_TYPE 0201LF
J 0
(-3275 5150);
DISPLAY 0.510638 (-3275 5150);
FORCEPROP 2 LAST CDS_LIB pure_quanta
J 0
(-2775 5150);
DISPLAY INVISIBLE (-2775 5150);
FORCEPROP 1 LAST WATTAGE 1/20W
J 2
(-2975 5225);
DISPLAY 0.510638 (-2975 5225);
DISPLAY INVISIBLE (-2975 5225);
FORCEPROP 1 LAST PATH I75
J 0
(-2825 5300);
DISPLAY 0.978723 (-2825 5300);
PAINT WHITE (-2825 5300);
DISPLAY INVISIBLE (-2825 5300);
FORCEPROP 1 LAST PART_NUMBER CS00001JE10
J 0
(-2825 5275);
DISPLAY 0.510638 (-2825 5275);
DISPLAY INVISIBLE (-2825 5275);
FORCEADD Q_RES..1
(-2775 5350);
FORCEPROP 1 LAST LOCATION R828
J 0
(-2625 5350);
DISPLAY 0.638298 (-2625 5350);
FORCEPROP 0 LAST $SEC 1
J 0
(-2625 5400);
DISPLAY 0.680851 (-2625 5400);
PAINT MONO (-2625 5400);
DISPLAY INVISIBLE (-2625 5400);
FORCEPROP 0 LAST CDS_SEC 1
J 0
(-2625 5400);
DISPLAY 0.680851 (-2625 5400);
DISPLAY INVISIBLE (-2625 5400);
FORCEPROP 1 LASTPIN (-2875 5350) $PN 1
J 0
(-2863 5362);
DISPLAY 0.787234 (-2863 5362);
PAINT MONO (-2863 5362);
FORCEPROP 1 LASTPIN (-2675 5350) $PN 2
J 0
(-2713 5362);
DISPLAY 0.787234 (-2713 5362);
PAINT MONO (-2713 5362);
FORCEPROP 1 LAST PACK_TYPE 0201LF
J 0
(-3275 5350);
DISPLAY 0.510638 (-3275 5350);
FORCEPROP 1 LAST TOLERANCE 5%
J 0
(-3000 5350);
DISPLAY 0.510638 (-3000 5350);
FORCEPROP 1 LAST MATERIAL CHIP
J 0
(-3125 5350);
DISPLAY 0.510638 (-3125 5350);
FORCEPROP 1 LAST VALUE 0
J 2
(-2900 5350);
DISPLAY 0.510638 (-2900 5350);
FORCEPROP 2 LAST CDS_LIB pure_quanta
J 0
(-2775 5350);
DISPLAY INVISIBLE (-2775 5350);
FORCEPROP 1 LAST WATTAGE 1/20W
J 2
(-2975 5425);
DISPLAY 0.510638 (-2975 5425);
DISPLAY INVISIBLE (-2975 5425);
FORCEPROP 1 LAST PATH I76
J 0
(-2825 5500);
DISPLAY 0.978723 (-2825 5500);
PAINT WHITE (-2825 5500);
DISPLAY INVISIBLE (-2825 5500);
FORCEPROP 1 LAST PART_NUMBER CS00001JE10
J 0
(-2825 5475);
DISPLAY 0.510638 (-2825 5475);
DISPLAY INVISIBLE (-2825 5475);
FORCEADD Q_RES..1
(-2775 5300);
FORCEPROP 1 LAST LOCATION R829
J 0
(-2625 5300);
DISPLAY 0.638298 (-2625 5300);
FORCEPROP 0 LAST $SEC 1
J 0
(-2625 5350);
DISPLAY 0.680851 (-2625 5350);
PAINT MONO (-2625 5350);
DISPLAY INVISIBLE (-2625 5350);
FORCEPROP 0 LAST CDS_SEC 1
J 0
(-2625 5350);
DISPLAY 0.680851 (-2625 5350);
DISPLAY INVISIBLE (-2625 5350);
FORCEPROP 1 LASTPIN (-2875 5300) $PN 1
J 0
(-2863 5312);
DISPLAY 0.787234 (-2863 5312);
PAINT MONO (-2863 5312);
FORCEPROP 1 LASTPIN (-2675 5300) $PN 2
J 0
(-2713 5312);
DISPLAY 0.787234 (-2713 5312);
PAINT MONO (-2713 5312);
FORCEPROP 1 LAST MATERIAL CHIP
J 0
(-3125 5300);
DISPLAY 0.510638 (-3125 5300);
FORCEPROP 1 LAST VALUE 0
J 2
(-2900 5300);
DISPLAY 0.510638 (-2900 5300);
FORCEPROP 1 LAST TOLERANCE 5%
J 0
(-3000 5300);
DISPLAY 0.510638 (-3000 5300);
FORCEPROP 1 LAST PACK_TYPE 0201LF
J 0
(-3275 5300);
DISPLAY 0.510638 (-3275 5300);
FORCEPROP 2 LAST CDS_LIB pure_quanta
J 0
(-2775 5300);
DISPLAY INVISIBLE (-2775 5300);
FORCEPROP 1 LAST WATTAGE 1/20W
J 2
(-2975 5375);
DISPLAY 0.510638 (-2975 5375);
DISPLAY INVISIBLE (-2975 5375);
FORCEPROP 1 LAST PATH I77
J 0
(-2825 5450);
DISPLAY 0.978723 (-2825 5450);
PAINT WHITE (-2825 5450);
DISPLAY INVISIBLE (-2825 5450);
FORCEPROP 1 LAST PART_NUMBER CS00001JE10
J 0
(-2825 5425);
DISPLAY 0.510638 (-2825 5425);
DISPLAY INVISIBLE (-2825 5425);
FORCEADD Q_RES..1
(-2775 5250);
FORCEPROP 1 LAST LOCATION R830
J 0
(-2625 5250);
DISPLAY 0.638298 (-2625 5250);
FORCEPROP 0 LAST $SEC 1
J 0
(-2625 5300);
DISPLAY 0.680851 (-2625 5300);
PAINT MONO (-2625 5300);
DISPLAY INVISIBLE (-2625 5300);
FORCEPROP 0 LAST CDS_SEC 1
J 0
(-2625 5300);
DISPLAY 0.680851 (-2625 5300);
DISPLAY INVISIBLE (-2625 5300);
FORCEPROP 1 LASTPIN (-2875 5250) $PN 1
J 0
(-2863 5262);
DISPLAY 0.787234 (-2863 5262);
PAINT MONO (-2863 5262);
FORCEPROP 1 LASTPIN (-2675 5250) $PN 2
J 0
(-2713 5262);
DISPLAY 0.787234 (-2713 5262);
PAINT MONO (-2713 5262);
FORCEPROP 1 LAST MATERIAL CHIP
J 0
(-3125 5250);
DISPLAY 0.510638 (-3125 5250);
FORCEPROP 1 LAST VALUE 0
J 2
(-2900 5250);
DISPLAY 0.510638 (-2900 5250);
FORCEPROP 1 LAST TOLERANCE 5%
J 0
(-3000 5250);
DISPLAY 0.510638 (-3000 5250);
FORCEPROP 1 LAST PACK_TYPE 0201LF
J 0
(-3275 5250);
DISPLAY 0.510638 (-3275 5250);
FORCEPROP 1 LAST WATTAGE 1/20W
J 2
(-2975 5325);
DISPLAY 0.510638 (-2975 5325);
DISPLAY INVISIBLE (-2975 5325);
FORCEPROP 2 LAST CDS_LIB pure_quanta
J 0
(-2775 5250);
DISPLAY INVISIBLE (-2775 5250);
FORCEPROP 1 LAST PATH I78
J 0
(-2825 5400);
DISPLAY 0.978723 (-2825 5400);
PAINT WHITE (-2825 5400);
DISPLAY INVISIBLE (-2825 5400);
FORCEPROP 1 LAST PART_NUMBER CS00001JE10
J 0
(-2825 5375);
DISPLAY 0.510638 (-2825 5375);
DISPLAY INVISIBLE (-2825 5375);
FORCEADD Q_RES..1
(-2775 5400);
FORCEPROP 1 LAST LOCATION R799
J 0
(-2625 5400);
DISPLAY 0.638298 (-2625 5400);
FORCEPROP 2 LAST SEC 1
J 0
(-2825 5600);
DISPLAY 0.680851 (-2825 5600);
PAINT MONO (-2825 5600);
DISPLAY INVISIBLE (-2825 5600);
FORCEPROP 1 LASTPIN (-2875 5400) $PN 1
J 0
(-2863 5412);
DISPLAY 0.787234 (-2863 5412);
PAINT MONO (-2863 5412);
FORCEPROP 1 LASTPIN (-2675 5400) $PN 2
J 0
(-2713 5412);
DISPLAY 0.787234 (-2713 5412);
PAINT MONO (-2713 5412);
FORCEPROP 1 LAST MATERIAL CHIP
J 0
(-3125 5400);
DISPLAY 0.510638 (-3125 5400);
FORCEPROP 1 LAST PACK_TYPE 0201LF
J 0
(-3275 5400);
DISPLAY 0.510638 (-3275 5400);
FORCEPROP 1 LAST VALUE 0
J 2
(-2900 5400);
DISPLAY 0.510638 (-2900 5400);
FORCEPROP 1 LAST TOLERANCE 5%
J 0
(-3000 5400);
DISPLAY 0.510638 (-3000 5400);
FORCEPROP 1 LAST WATTAGE 1/20W
J 2
(-2975 5475);
DISPLAY 0.510638 (-2975 5475);
DISPLAY INVISIBLE (-2975 5475);
FORCEPROP 2 LAST SEC_TYPE 0201LF
J 0
(-2825 5600);
DISPLAY 0.680851 (-2825 5600);
DISPLAY INVISIBLE (-2825 5600);
FORCEPROP 2 LAST CDS_LIB pure_quanta
J 0
(-2775 5400);
DISPLAY INVISIBLE (-2775 5400);
FORCEPROP 1 LAST PATH I79
J 0
(-2825 5550);
DISPLAY 0.978723 (-2825 5550);
PAINT WHITE (-2825 5550);
DISPLAY INVISIBLE (-2825 5550);
FORCEPROP 1 LAST PART_NUMBER CS00001JE10
J 0
(-2825 5525);
DISPLAY 0.510638 (-2825 5525);
DISPLAY INVISIBLE (-2825 5525);
FORCEADD Q_RES..2
(-7875 1300);
FORCEPROP 1 LAST LOCATION R847
J 0
(-7830 1425);
DISPLAY 0.787234 (-7830 1425);
FORCEPROP 0 LAST $SEC 1
J 0
(-7825 1475);
DISPLAY 0.680851 (-7825 1475);
PAINT MONO (-7825 1475);
DISPLAY INVISIBLE (-7825 1475);
FORCEPROP 0 LAST CDS_SEC 1
J 0
(-7825 1475);
DISPLAY 0.680851 (-7825 1475);
DISPLAY INVISIBLE (-7825 1475);
FORCEPROP 1 LASTPIN (-7875 1400) $PN 1
J 0
(-7870 1362);
DISPLAY 0.787234 (-7870 1362);
PAINT MONO (-7870 1362);
FORCEPROP 1 LASTPIN (-7875 1200) $PN 2
J 0
(-7870 1210);
DISPLAY 0.787234 (-7870 1210);
PAINT MONO (-7870 1210);
FORCEPROP 1 LAST VALUE 4.7K
J 0
(-7830 1375);
DISPLAY 0.787234 (-7830 1375);
FORCEPROP 1 LAST TOLERANCE 5%
J 0
(-7830 1325);
DISPLAY 0.787234 (-7830 1325);
FORCEPROP 1 LAST WATTAGE 1/20W
J 0
(-7835 1275);
DISPLAY 0.787234 (-7835 1275);
FORCEPROP 1 LAST MATERIAL CHIP
J 0
(-7835 1225);
DISPLAY 0.787234 (-7835 1225);
FORCEPROP 1 LAST PACK_TYPE 0201LF
J 0
(-7835 1125);
DISPLAY 0.787234 (-7835 1125);
FORCEPROP 2 LAST CDS_LIB pure_quanta
J 0
(-7875 1300);
DISPLAY INVISIBLE (-7875 1300);
FORCEPROP 1 LAST PATH I8
J 0
(-7825 1475);
DISPLAY 0.978723 (-7825 1475);
PAINT WHITE (-7825 1475);
DISPLAY INVISIBLE (-7825 1475);
FORCEPROP 1 LAST PART_NUMBER CS24701JE04
J 0
(-7835 1175);
DISPLAY 0.978723 (-7835 1175);
DISPLAY INVISIBLE (-7835 1175);
FORCEADD Q_RES..1
(-2775 5450);
FORCEPROP 1 LAST LOCATION R797
J 0
(-2625 5450);
DISPLAY 0.638298 (-2625 5450);
FORCEPROP 2 LAST SEC 1
J 0
(-2825 5650);
DISPLAY 0.680851 (-2825 5650);
PAINT MONO (-2825 5650);
DISPLAY INVISIBLE (-2825 5650);
FORCEPROP 1 LASTPIN (-2875 5450) $PN 1
J 0
(-2863 5462);
DISPLAY 0.787234 (-2863 5462);
PAINT MONO (-2863 5462);
FORCEPROP 1 LASTPIN (-2675 5450) $PN 2
J 0
(-2713 5462);
DISPLAY 0.787234 (-2713 5462);
PAINT MONO (-2713 5462);
FORCEPROP 1 LAST MATERIAL CHIP
J 0
(-3125 5450);
DISPLAY 0.510638 (-3125 5450);
FORCEPROP 1 LAST PACK_TYPE 0201LF
J 0
(-3275 5450);
DISPLAY 0.510638 (-3275 5450);
FORCEPROP 1 LAST VALUE 0
J 2
(-2900 5450);
DISPLAY 0.510638 (-2900 5450);
FORCEPROP 1 LAST TOLERANCE 5%
J 0
(-3000 5450);
DISPLAY 0.510638 (-3000 5450);
FORCEPROP 2 LAST CDS_LIB pure_quanta
J 0
(-2775 5450);
DISPLAY INVISIBLE (-2775 5450);
FORCEPROP 2 LAST SEC_TYPE 0201LF
J 0
(-2825 5650);
DISPLAY 0.680851 (-2825 5650);
DISPLAY INVISIBLE (-2825 5650);
FORCEPROP 1 LAST WATTAGE 1/20W
J 2
(-2975 5525);
DISPLAY 0.510638 (-2975 5525);
DISPLAY INVISIBLE (-2975 5525);
FORCEPROP 1 LAST PATH I80
J 0
(-2825 5600);
DISPLAY 0.978723 (-2825 5600);
PAINT WHITE (-2825 5600);
DISPLAY INVISIBLE (-2825 5600);
FORCEPROP 1 LAST PART_NUMBER CS00001JE10
J 0
(-2825 5575);
DISPLAY 0.510638 (-2825 5575);
DISPLAY INVISIBLE (-2825 5575);
FORCEADD Q_RES..1
(-3025 5700);
FORCEPROP 1 LAST LOCATION R850
J 0
(-2875 5700);
DISPLAY 0.638298 (-2875 5700);
PAINT SKYBLUE (-2875 5700);
FORCEPROP 0 LAST $SEC 1
J 0
(-2875 5750);
DISPLAY 0.680851 (-2875 5750);
PAINT MONO (-2875 5750);
DISPLAY INVISIBLE (-2875 5750);
FORCEPROP 0 LAST CDS_SEC 1
J 0
(-2875 5750);
DISPLAY 0.680851 (-2875 5750);
DISPLAY INVISIBLE (-2875 5750);
FORCEPROP 1 LASTPIN (-3125 5700) $PN 1
J 0
(-3113 5712);
DISPLAY 0.787234 (-3113 5712);
PAINT MONO (-3113 5712);
FORCEPROP 1 LASTPIN (-2925 5700) $PN 2
J 0
(-2963 5712);
DISPLAY 0.787234 (-2963 5712);
PAINT MONO (-2963 5712);
FORCEPROP 1 LAST PACK_TYPE 0201LF
J 0
(-3525 5700);
DISPLAY 0.510638 (-3525 5700);
FORCEPROP 1 LAST VALUE 0
J 2
(-3150 5700);
DISPLAY 0.510638 (-3150 5700);
FORCEPROP 1 LAST MATERIAL CHIP
J 0
(-3375 5700);
DISPLAY 0.510638 (-3375 5700);
FORCEPROP 1 LAST TOLERANCE 5%
J 0
(-3250 5700);
DISPLAY 0.510638 (-3250 5700);
FORCEPROP 2 LAST CDS_LIB pure_quanta
J 0
(-3025 5700);
DISPLAY INVISIBLE (-3025 5700);
FORCEPROP 1 LAST WATTAGE 1/20W
J 2
(-3225 5775);
DISPLAY 0.510638 (-3225 5775);
DISPLAY INVISIBLE (-3225 5775);
FORCEPROP 1 LAST PATH I81
J 0
(-3075 5850);
DISPLAY 0.978723 (-3075 5850);
PAINT WHITE (-3075 5850);
DISPLAY INVISIBLE (-3075 5850);
FORCEPROP 1 LAST PART_NUMBER CS00001JE10
J 0
(-3075 5825);
DISPLAY 0.510638 (-3075 5825);
DISPLAY INVISIBLE (-3075 5825);
FORCEADD Q_RES..1
(-3025 5650);
FORCEPROP 1 LAST LOCATION R851
J 0
(-2875 5650);
DISPLAY 0.638298 (-2875 5650);
PAINT SKYBLUE (-2875 5650);
FORCEPROP 0 LAST $SEC 1
J 0
(-2875 5700);
DISPLAY 0.680851 (-2875 5700);
PAINT MONO (-2875 5700);
DISPLAY INVISIBLE (-2875 5700);
FORCEPROP 0 LAST CDS_SEC 1
J 0
(-2875 5700);
DISPLAY 0.680851 (-2875 5700);
DISPLAY INVISIBLE (-2875 5700);
FORCEPROP 1 LASTPIN (-3125 5650) $PN 1
J 0
(-3113 5662);
DISPLAY 0.787234 (-3113 5662);
PAINT MONO (-3113 5662);
FORCEPROP 1 LASTPIN (-2925 5650) $PN 2
J 0
(-2963 5662);
DISPLAY 0.787234 (-2963 5662);
PAINT MONO (-2963 5662);
FORCEPROP 1 LAST TOLERANCE 5%
J 0
(-3250 5650);
DISPLAY 0.510638 (-3250 5650);
FORCEPROP 1 LAST MATERIAL CHIP
J 0
(-3375 5650);
DISPLAY 0.510638 (-3375 5650);
FORCEPROP 1 LAST PACK_TYPE 0201LF
J 0
(-3525 5650);
DISPLAY 0.510638 (-3525 5650);
FORCEPROP 1 LAST VALUE 0
J 2
(-3150 5650);
DISPLAY 0.510638 (-3150 5650);
FORCEPROP 1 LAST WATTAGE 1/20W
J 2
(-3225 5725);
DISPLAY 0.510638 (-3225 5725);
DISPLAY INVISIBLE (-3225 5725);
FORCEPROP 2 LAST CDS_LIB pure_quanta
J 0
(-3025 5650);
DISPLAY INVISIBLE (-3025 5650);
FORCEPROP 1 LAST PATH I82
J 0
(-3075 5800);
DISPLAY 0.978723 (-3075 5800);
PAINT WHITE (-3075 5800);
DISPLAY INVISIBLE (-3075 5800);
FORCEPROP 1 LAST PART_NUMBER CS00001JE10
J 0
(-3075 5775);
DISPLAY 0.510638 (-3075 5775);
DISPLAY INVISIBLE (-3075 5775);
FORCEADD OFFPAGE..2
(-1325 5100);
FORCEPROP 2 LAST $XR0 186 
J 0
(-1136 5100);
DISPLAY 0.638298 (-1136 5100);
PAINT MONO (-1136 5100);
FORCEPROP 2 LAST CDS_LIB standard
J 0
(-1325 5100);
DISPLAY INVISIBLE (-1325 5100);
FORCEPROP 1 LAST OFFPAGE TRUE
J 0
(-1000 4975);
DISPLAY 0.872340 (-1000 4975);
PAINT GREEN (-1000 4975);
DISPLAY INVISIBLE (-1000 4975);
FORCEPROP 1 LAST COMMENT_BODY TRUE
J 0
(-1370 5005);
DISPLAY 0.872340 (-1370 5005);
PAINT GREEN (-1370 5005);
DISPLAY INVISIBLE (-1370 5005);
FORCEPROP 2 LAST PATH I83
J 0
(-1100 5150);
DISPLAY 0.680851 (-1100 5150);
DISPLAY INVISIBLE (-1100 5150);
FORCEADD OFFPAGE..3
(-1325 5150);
FORCEPROP 2 LAST $XR0 186 
J 0
(-1111 5150);
DISPLAY 0.638298 (-1111 5150);
PAINT MONO (-1111 5150);
FORCEPROP 2 LAST CDS_LIB standard
J 0
(-1325 5150);
DISPLAY INVISIBLE (-1325 5150);
FORCEPROP 1 LAST OFFPAGE TRUE
J 0
(-1000 5025);
DISPLAY 0.872340 (-1000 5025);
PAINT GREEN (-1000 5025);
DISPLAY INVISIBLE (-1000 5025);
FORCEPROP 1 LAST COMMENT_BODY TRUE
J 0
(-1375 5050);
DISPLAY 0.872340 (-1375 5050);
PAINT GREEN (-1375 5050);
DISPLAY INVISIBLE (-1375 5050);
FORCEPROP 2 LAST PATH I84
J 0
(-1100 5200);
DISPLAY 0.680851 (-1100 5200);
DISPLAY INVISIBLE (-1100 5200);
FORCEADD OFFPAGE..2
(-1325 5200);
FORCEPROP 2 LAST $XR0 186 
J 0
(-1136 5200);
DISPLAY 0.638298 (-1136 5200);
PAINT MONO (-1136 5200);
FORCEPROP 2 LAST CDS_LIB standard
J 0
(-1325 5200);
DISPLAY INVISIBLE (-1325 5200);
FORCEPROP 1 LAST OFFPAGE TRUE
J 0
(-1000 5075);
DISPLAY 0.872340 (-1000 5075);
PAINT GREEN (-1000 5075);
DISPLAY INVISIBLE (-1000 5075);
FORCEPROP 1 LAST COMMENT_BODY TRUE
J 0
(-1370 5105);
DISPLAY 0.872340 (-1370 5105);
PAINT GREEN (-1370 5105);
DISPLAY INVISIBLE (-1370 5105);
FORCEPROP 2 LAST PATH I85
J 0
(-1100 5250);
DISPLAY 0.680851 (-1100 5250);
DISPLAY INVISIBLE (-1100 5250);
FORCEADD OFFPAGE..2
(-1325 5300);
FORCEPROP 2 LAST $XR0 186 
J 0
(-1136 5300);
DISPLAY 0.638298 (-1136 5300);
PAINT MONO (-1136 5300);
FORCEPROP 2 LAST CDS_LIB standard
J 0
(-1325 5300);
DISPLAY INVISIBLE (-1325 5300);
FORCEPROP 1 LAST OFFPAGE TRUE
J 0
(-1000 5175);
DISPLAY 0.872340 (-1000 5175);
PAINT GREEN (-1000 5175);
DISPLAY INVISIBLE (-1000 5175);
FORCEPROP 1 LAST COMMENT_BODY TRUE
J 0
(-1370 5205);
DISPLAY 0.872340 (-1370 5205);
PAINT GREEN (-1370 5205);
DISPLAY INVISIBLE (-1370 5205);
FORCEPROP 2 LAST PATH I86
J 0
(-1100 5350);
DISPLAY 0.680851 (-1100 5350);
DISPLAY INVISIBLE (-1100 5350);
FORCEADD OFFPAGE..3
(-1325 5250);
FORCEPROP 2 LAST $XR0 186 
J 0
(-1111 5250);
DISPLAY 0.638298 (-1111 5250);
PAINT MONO (-1111 5250);
FORCEPROP 2 LAST CDS_LIB standard
J 0
(-1325 5250);
DISPLAY INVISIBLE (-1325 5250);
FORCEPROP 1 LAST OFFPAGE TRUE
J 0
(-1000 5125);
DISPLAY 0.872340 (-1000 5125);
PAINT GREEN (-1000 5125);
DISPLAY INVISIBLE (-1000 5125);
FORCEPROP 1 LAST COMMENT_BODY TRUE
J 0
(-1375 5150);
DISPLAY 0.872340 (-1375 5150);
PAINT GREEN (-1375 5150);
DISPLAY INVISIBLE (-1375 5150);
FORCEPROP 2 LAST PATH I87
J 0
(-1100 5300);
DISPLAY 0.680851 (-1100 5300);
DISPLAY INVISIBLE (-1100 5300);
FORCEADD OFFPAGE..3
(-1325 5350);
FORCEPROP 2 LAST $XR0 186 
J 0
(-1111 5350);
DISPLAY 0.638298 (-1111 5350);
PAINT MONO (-1111 5350);
FORCEPROP 2 LAST CDS_LIB standard
J 0
(-1325 5350);
DISPLAY INVISIBLE (-1325 5350);
FORCEPROP 1 LAST OFFPAGE TRUE
J 0
(-1000 5225);
DISPLAY 0.872340 (-1000 5225);
PAINT GREEN (-1000 5225);
DISPLAY INVISIBLE (-1000 5225);
FORCEPROP 1 LAST COMMENT_BODY TRUE
J 0
(-1375 5250);
DISPLAY 0.872340 (-1375 5250);
PAINT GREEN (-1375 5250);
DISPLAY INVISIBLE (-1375 5250);
FORCEPROP 2 LAST PATH I88
J 0
(-1100 5400);
DISPLAY 0.680851 (-1100 5400);
DISPLAY INVISIBLE (-1100 5400);
FORCEADD OFFPAGE..3
(-1325 5450);
FORCEPROP 2 LAST $XR0 186 
J 0
(-1111 5450);
DISPLAY 0.638298 (-1111 5450);
PAINT MONO (-1111 5450);
FORCEPROP 2 LAST CDS_LIB standard
J 0
(-1325 5450);
DISPLAY INVISIBLE (-1325 5450);
FORCEPROP 1 LAST OFFPAGE TRUE
J 0
(-1000 5325);
DISPLAY 0.872340 (-1000 5325);
PAINT GREEN (-1000 5325);
DISPLAY INVISIBLE (-1000 5325);
FORCEPROP 1 LAST COMMENT_BODY TRUE
J 0
(-1375 5350);
DISPLAY 0.872340 (-1375 5350);
PAINT GREEN (-1375 5350);
DISPLAY INVISIBLE (-1375 5350);
FORCEPROP 2 LAST PATH I89
J 0
(-1100 5500);
DISPLAY 0.680851 (-1100 5500);
DISPLAY INVISIBLE (-1100 5500);
FORCEADD Q_RES..2
(-7875 2050);
FORCEPROP 1 LAST LOCATION R844
J 0
(-7830 2175);
DISPLAY 0.787234 (-7830 2175);
FORCEPROP 0 LAST $SEC 1
J 0
(-7825 2225);
DISPLAY 0.680851 (-7825 2225);
PAINT MONO (-7825 2225);
DISPLAY INVISIBLE (-7825 2225);
FORCEPROP 0 LAST CDS_SEC 1
J 0
(-7825 2225);
DISPLAY 0.680851 (-7825 2225);
DISPLAY INVISIBLE (-7825 2225);
FORCEPROP 1 LASTPIN (-7875 2150) $PN 1
J 0
(-7870 2112);
DISPLAY 0.787234 (-7870 2112);
PAINT MONO (-7870 2112);
FORCEPROP 1 LASTPIN (-7875 1950) $PN 2
J 0
(-7870 1960);
DISPLAY 0.787234 (-7870 1960);
PAINT MONO (-7870 1960);
FORCEPROP 1 LAST PACK_TYPE 0201LF
J 0
(-7825 1900);
DISPLAY 0.787234 (-7825 1900);
FORCEPROP 1 LAST WATTAGE 1/20W
J 0
(-7835 2025);
DISPLAY 0.787234 (-7835 2025);
FORCEPROP 1 LAST TOLERANCE 5%
J 0
(-7830 2075);
DISPLAY 0.787234 (-7830 2075);
FORCEPROP 1 LAST VALUE 4.7K
J 0
(-7830 2125);
DISPLAY 0.787234 (-7830 2125);
FORCEPROP 1 LAST MATERIAL EMPTY
J 0
(-7835 1975);
DISPLAY 0.787234 (-7835 1975);
FORCEPROP 2 LAST CDS_LIB pure_quanta
J 0
(-7875 2050);
DISPLAY INVISIBLE (-7875 2050);
FORCEPROP 1 LAST PATH I9
J 0
(-7825 2225);
DISPLAY 0.978723 (-7825 2225);
PAINT WHITE (-7825 2225);
DISPLAY INVISIBLE (-7825 2225);
FORCEPROP 1 LAST PART_NUMBER CS24701JE04
J 0
(-7835 1925);
DISPLAY 0.978723 (-7835 1925);
DISPLAY INVISIBLE (-7835 1925);
FORCEADD OFFPAGE..2
(-1300 5400);
FORCEPROP 2 LAST $XR0 186 
J 0
(-1111 5400);
DISPLAY 0.638298 (-1111 5400);
PAINT MONO (-1111 5400);
FORCEPROP 2 LAST CDS_LIB standard
J 0
(-1300 5400);
DISPLAY INVISIBLE (-1300 5400);
FORCEPROP 1 LAST OFFPAGE TRUE
J 0
(-975 5275);
DISPLAY 0.872340 (-975 5275);
PAINT GREEN (-975 5275);
DISPLAY INVISIBLE (-975 5275);
FORCEPROP 1 LAST COMMENT_BODY TRUE
J 0
(-1345 5305);
DISPLAY 0.872340 (-1345 5305);
PAINT GREEN (-1345 5305);
DISPLAY INVISIBLE (-1345 5305);
FORCEPROP 2 LAST PATH I90
J 0
(-1100 5450);
DISPLAY 0.680851 (-1100 5450);
DISPLAY INVISIBLE (-1100 5450);
FORCEADD OFFPAGE..1
R 2
(-1625 5650);
FORCEPROP 2 LAST $XR0 151 
J 0
(-1439 5650);
DISPLAY 0.638298 (-1439 5650);
PAINT MONO (-1439 5650);
FORCEPROP 2 LAST CDS_LIB standard
J 2
(-1625 5650);
DISPLAY INVISIBLE (-1625 5650);
FORCEPROP 1 LAST OFFPAGE TRUE
J 2
(-1950 5525);
DISPLAY 1.170213 (-1950 5525);
PAINT GREEN (-1950 5525);
DISPLAY INVISIBLE (-1950 5525);
FORCEPROP 1 LAST COMMENT_BODY TRUE
J 2
(-1750 5550);
DISPLAY 1.170213 (-1750 5550);
PAINT GREEN (-1750 5550);
DISPLAY INVISIBLE (-1750 5550);
FORCEPROP 2 LAST PATH I91
J 0
(-1450 5725);
DISPLAY 0.680851 (-1450 5725);
DISPLAY INVISIBLE (-1450 5725);
FORCEADD OFFPAGE..3
(-1650 5700);
FORCEPROP 2 LAST $XR0 151 
J 0
(-1436 5700);
DISPLAY 0.638298 (-1436 5700);
PAINT MONO (-1436 5700);
FORCEPROP 2 LAST CDS_LIB standard
J 0
(-1650 5700);
DISPLAY INVISIBLE (-1650 5700);
FORCEPROP 1 LAST OFFPAGE TRUE
J 0
(-1325 5575);
DISPLAY 0.872340 (-1325 5575);
PAINT GREEN (-1325 5575);
DISPLAY INVISIBLE (-1325 5575);
FORCEPROP 1 LAST COMMENT_BODY TRUE
J 0
(-1700 5600);
DISPLAY 0.872340 (-1700 5600);
PAINT GREEN (-1700 5600);
DISPLAY INVISIBLE (-1700 5600);
FORCEPROP 2 LAST PATH I92
J 0
(-1450 5775);
DISPLAY 0.680851 (-1450 5775);
DISPLAY INVISIBLE (-1450 5775);
FORCEADD OFFPAGE..2
(-700 1375);
FORCEPROP 2 LAST $XR1 356 
J 0
(-391 1375);
DISPLAY 0.638298 (-391 1375);
PAINT MONO (-391 1375);
FORCEPROP 2 LAST $XR0 186 
J 0
(-511 1375);
DISPLAY 0.638298 (-511 1375);
PAINT MONO (-511 1375);
FORCEPROP 2 LAST CDS_LIB standard
J 0
(-700 1375);
DISPLAY INVISIBLE (-700 1375);
FORCEPROP 1 LAST OFFPAGE TRUE
J 0
(-375 1250);
DISPLAY 0.872340 (-375 1250);
PAINT GREEN (-375 1250);
DISPLAY INVISIBLE (-375 1250);
FORCEPROP 1 LAST COMMENT_BODY TRUE
J 0
(-745 1280);
DISPLAY 0.872340 (-745 1280);
PAINT GREEN (-745 1280);
DISPLAY INVISIBLE (-745 1280);
FORCEPROP 2 LAST PATH I93
J 0
(-500 1425);
DISPLAY 0.680851 (-500 1425);
DISPLAY INVISIBLE (-500 1425);
FORCEADD TCA9548APWR..1
(-4825 5425);
FORCEPROP 1 LAST LOCATION U22
J 0
(-5025 6005);
DISPLAY 0.723404 (-5025 6005);
PAINT GREEN (-5025 6005);
FORCEPROP 0 LAST $SEC 1
J 0
(-5025 6150);
DISPLAY 0.680851 (-5025 6150);
PAINT MONO (-5025 6150);
DISPLAY INVISIBLE (-5025 6150);
FORCEPROP 0 LAST CDS_SEC 1
J 0
(-5025 6150);
DISPLAY 0.680851 (-5025 6150);
DISPLAY INVISIBLE (-5025 6150);
FORCEPROP 0 LASTPIN (-5175 5750) $PN 1
J 2
(-5185 5760);
DISPLAY 0.680851 (-5185 5760);
PAINT MONO (-5185 5760);
FORCEPROP 0 LASTPIN (-5175 5700) $PN 2
J 2
(-5185 5710);
DISPLAY 0.680851 (-5185 5710);
PAINT MONO (-5185 5710);
FORCEPROP 0 LASTPIN (-5175 5650) $PN 21
J 2
(-5185 5660);
DISPLAY 0.680851 (-5185 5660);
PAINT MONO (-5185 5660);
FORCEPROP 0 LASTPIN (-4475 5000) $PN 12
J 0
(-4465 5010);
DISPLAY 0.680851 (-4465 5010);
PAINT MONO (-4465 5010);
FORCEPROP 0 LASTPIN (-5175 5550) $PN 3
J 2
(-5185 5560);
DISPLAY 0.680851 (-5185 5560);
PAINT MONO (-5185 5560);
FORCEPROP 0 LASTPIN (-5175 5400) $PN 5
J 2
(-5185 5410);
DISPLAY 0.680851 (-5185 5410);
PAINT MONO (-5185 5410);
FORCEPROP 0 LASTPIN (-5175 5300) $PN 7
J 2
(-5185 5310);
DISPLAY 0.680851 (-5185 5310);
PAINT MONO (-5185 5310);
FORCEPROP 0 LASTPIN (-5175 5200) $PN 9
J 2
(-5185 5210);
DISPLAY 0.680851 (-5185 5210);
PAINT MONO (-5185 5210);
FORCEPROP 0 LASTPIN (-5175 5100) $PN 11
J 2
(-5185 5110);
DISPLAY 0.680851 (-5185 5110);
PAINT MONO (-5185 5110);
FORCEPROP 0 LASTPIN (-4475 5400) $PN 14
J 0
(-4465 5410);
DISPLAY 0.680851 (-4465 5410);
PAINT MONO (-4465 5410);
FORCEPROP 0 LASTPIN (-4475 5300) $PN 16
J 0
(-4465 5310);
DISPLAY 0.680851 (-4465 5310);
PAINT MONO (-4465 5310);
FORCEPROP 0 LASTPIN (-4475 5200) $PN 18
J 0
(-4465 5210);
DISPLAY 0.680851 (-4465 5210);
PAINT MONO (-4465 5210);
FORCEPROP 0 LASTPIN (-4475 5100) $PN 20
J 0
(-4465 5110);
DISPLAY 0.680851 (-4465 5110);
PAINT MONO (-4465 5110);
FORCEPROP 0 LASTPIN (-4475 5650) $PN 22
J 0
(-4465 5660);
DISPLAY 0.680851 (-4465 5660);
PAINT MONO (-4465 5660);
FORCEPROP 0 LASTPIN (-5175 5450) $PN 4
J 2
(-5185 5460);
DISPLAY 0.680851 (-5185 5460);
PAINT MONO (-5185 5460);
FORCEPROP 0 LASTPIN (-5175 5350) $PN 6
J 2
(-5185 5360);
DISPLAY 0.680851 (-5185 5360);
PAINT MONO (-5185 5360);
FORCEPROP 0 LASTPIN (-5175 5250) $PN 8
J 2
(-5185 5260);
DISPLAY 0.680851 (-5185 5260);
PAINT MONO (-5185 5260);
FORCEPROP 0 LASTPIN (-5175 5150) $PN 10
J 2
(-5185 5160);
DISPLAY 0.680851 (-5185 5160);
PAINT MONO (-5185 5160);
FORCEPROP 0 LASTPIN (-4475 5450) $PN 13
J 0
(-4465 5460);
DISPLAY 0.680851 (-4465 5460);
PAINT MONO (-4465 5460);
FORCEPROP 0 LASTPIN (-4475 5350) $PN 15
J 0
(-4465 5360);
DISPLAY 0.680851 (-4465 5360);
PAINT MONO (-4465 5360);
FORCEPROP 0 LASTPIN (-4475 5250) $PN 17
J 0
(-4465 5260);
DISPLAY 0.680851 (-4465 5260);
PAINT MONO (-4465 5260);
FORCEPROP 0 LASTPIN (-4475 5150) $PN 19
J 0
(-4465 5160);
DISPLAY 0.680851 (-4465 5160);
PAINT MONO (-4465 5160);
FORCEPROP 0 LASTPIN (-4475 5700) $PN 23
J 0
(-4465 5710);
DISPLAY 0.680851 (-4465 5710);
PAINT MONO (-4465 5710);
FORCEPROP 0 LASTPIN (-5175 5850) $PN 24
J 2
(-5185 5860);
DISPLAY 0.680851 (-5185 5860);
PAINT MONO (-5185 5860);
FORCEPROP 2 LAST VALUE TCA9548APWR
J 0
(-5025 6050);
DISPLAY 1.021277 (-5025 6050);
FORCEPROP 1 LAST MATERIAL IC
J 0
(-5025 5905);
DISPLAY 0.723404 (-5025 5905);
PAINT GREEN (-5025 5905);
FORCEPROP 2 LAST PART_TYPE SMLF
J 0
(-5025 6100);
DISPLAY 1.021277 (-5025 6100);
FORCEPROP 2 LAST CDS_LIB pure_quanta
J 0
(-4825 5425);
DISPLAY INVISIBLE (-4825 5425);
FORCEPROP 1 LAST CDS_LMAN_SYM_OUTLINE -200,475,200,-475
J 0
(-4825 5425);
DISPLAY 0.468085 (-4825 5425);
PAINT GREEN (-4825 5425);
DISPLAY INVISIBLE (-4825 5425);
FORCEPROP 1 LAST NEEDS_NO_SIZE TRUE
J 0
(-4825 5425);
DISPLAY 0.723404 (-4825 5425);
PAINT GREEN (-4825 5425);
DISPLAY INVISIBLE (-4825 5425);
FORCEPROP 1 LAST PATH I94
J 0
(-4825 5425);
DISPLAY 0.723404 (-4825 5425);
PAINT GREEN (-4825 5425);
DISPLAY INVISIBLE (-4825 5425);
FORCEPROP 1 LAST PART_NUMBER AL009548K02
J 0
(-5025 5952);
DISPLAY 0.723404 (-5025 5952);
PAINT GREEN (-5025 5952);
DISPLAY INVISIBLE (-5025 5952);
FORCEADD P1V0_AUX..1
(-8525 2500);
FORCEPROP 3 LASTPIN (-8525 2450) SIG_NAME P1V8_AUX\g
J 0
(-8515 2460);
DISPLAY 0.659574 (-8515 2460);
PAINT MONO (-8515 2460);
DISPLAY INVISIBLE (-8515 2460);
FORCEPROP 1 LAST HDL_POWER P1V8_AUX
J 1
(-8515 2540);
DISPLAY 0.489362 (-8515 2540);
PAINT GREEN (-8515 2540);
FORCEPROP 2 LAST CDS_LIB pure_quanta_power
J 0
(-8525 2500);
DISPLAY INVISIBLE (-8525 2500);
FORCEPROP 1 LAST PATH I95
J 0
(-8475 2525);
DISPLAY 0.872340 (-8475 2525);
PAINT AQUA (-8475 2525);
DISPLAY INVISIBLE (-8475 2525);
FORCEADD OFFPAGE..2
(-775 2625);
FORCEPROP 2 LAST $XR0 185 
J 0
(-586 2625);
DISPLAY 0.638298 (-586 2625);
PAINT MONO (-586 2625);
FORCEPROP 2 LAST CDS_LIB standard
J 0
(-775 2625);
DISPLAY INVISIBLE (-775 2625);
FORCEPROP 1 LAST OFFPAGE TRUE
J 0
(-450 2500);
DISPLAY 0.872340 (-450 2500);
PAINT GREEN (-450 2500);
DISPLAY INVISIBLE (-450 2500);
FORCEPROP 1 LAST COMMENT_BODY TRUE
J 0
(-820 2530);
DISPLAY 0.872340 (-820 2530);
PAINT GREEN (-820 2530);
DISPLAY INVISIBLE (-820 2530);
FORCEPROP 2 LAST PATH I96
J 0
(-600 2700);
DISPLAY 0.680851 (-600 2700);
DISPLAY INVISIBLE (-600 2700);
FORCEADD OFFPAGE..2
(-775 2575);
FORCEPROP 2 LAST $XR0 185 
J 0
(-586 2575);
DISPLAY 0.638298 (-586 2575);
PAINT MONO (-586 2575);
FORCEPROP 2 LAST CDS_LIB standard
J 0
(-775 2575);
DISPLAY INVISIBLE (-775 2575);
FORCEPROP 1 LAST OFFPAGE TRUE
J 0
(-450 2450);
DISPLAY 0.872340 (-450 2450);
PAINT GREEN (-450 2450);
DISPLAY INVISIBLE (-450 2450);
FORCEPROP 1 LAST COMMENT_BODY TRUE
J 0
(-820 2480);
DISPLAY 0.872340 (-820 2480);
PAINT GREEN (-820 2480);
DISPLAY INVISIBLE (-820 2480);
FORCEPROP 2 LAST PATH I97
J 0
(-600 2650);
DISPLAY 0.680851 (-600 2650);
DISPLAY INVISIBLE (-600 2650);
FORCEADD OFFPAGE..2
(-775 2525);
FORCEPROP 2 LAST $XR0 185 
J 0
(-586 2525);
DISPLAY 0.638298 (-586 2525);
PAINT MONO (-586 2525);
FORCEPROP 2 LAST CDS_LIB standard
J 0
(-775 2525);
DISPLAY INVISIBLE (-775 2525);
FORCEPROP 1 LAST OFFPAGE TRUE
J 0
(-450 2400);
DISPLAY 0.872340 (-450 2400);
PAINT GREEN (-450 2400);
DISPLAY INVISIBLE (-450 2400);
FORCEPROP 1 LAST COMMENT_BODY TRUE
J 0
(-820 2430);
DISPLAY 0.872340 (-820 2430);
PAINT GREEN (-820 2430);
DISPLAY INVISIBLE (-820 2430);
FORCEPROP 2 LAST PATH I98
J 0
(-600 2600);
DISPLAY 0.680851 (-600 2600);
DISPLAY INVISIBLE (-600 2600);
FORCEADD OFFPAGE..2
(-775 2475);
FORCEPROP 2 LAST $XR0 185 
J 0
(-586 2475);
DISPLAY 0.638298 (-586 2475);
PAINT MONO (-586 2475);
FORCEPROP 2 LAST CDS_LIB standard
J 0
(-775 2475);
DISPLAY INVISIBLE (-775 2475);
FORCEPROP 1 LAST OFFPAGE TRUE
J 0
(-450 2350);
DISPLAY 0.872340 (-450 2350);
PAINT GREEN (-450 2350);
DISPLAY INVISIBLE (-450 2350);
FORCEPROP 1 LAST COMMENT_BODY TRUE
J 0
(-820 2380);
DISPLAY 0.872340 (-820 2380);
PAINT GREEN (-820 2380);
DISPLAY INVISIBLE (-820 2380);
FORCEPROP 2 LAST PATH I99
J 0
(-600 2550);
DISPLAY 0.680851 (-600 2550);
DISPLAY INVISIBLE (-600 2550);
FORCEADD DNS..1
(-7775 1975);
PAINT RED (-7775 1975);
FORCEPROP 2 LAST CDS_LIB mstr_misc
J 0
(-7775 1975);
DISPLAY INVISIBLE (-7775 1975);
FORCEPROP 1 LAST COMMENT_BODY TRUE
R 1
J 0
(-7700 1750);
DISPLAY 0.872340 (-7700 1750);
PAINT GREEN (-7700 1750);
DISPLAY INVISIBLE (-7700 1750);
FORCEADD QUANTA_TITLE_BLOCK_C..1
(0 0);
FORCEPROP 0 LAST CDS_CON_LAST_MODIFIED Thu Sep 14 16:13:05 2023
J 0
(-1885 15);
DISPLAY INVISIBLE (-1885 15);
FORCEPROP 1 LAST CUSTOM_TXT_CDS <CON_LAST_MODIFIED>
J 0
(-1885 15);
DISPLAY 0.978723 (-1885 15);
FORCEPROP 2 LAST CUSTOM_TXT_CDS <XR_PAGE_TITLE>
J 0
(-7890 5250);
DISPLAY 0.638298 (-7890 5250);
PAINT PINK (-7890 5250);
DISPLAY INVISIBLE (-7890 5250);
FORCEPROP 1 LAST CUSTOM_TXT_CDS <NAME_2>
J 0
(-3175 50);
FORCEPROP 1 LAST CUSTOM_TXT_CDS <NAME_1>
J 0
(-3175 175);
FORCEPROP 1 LAST CUSTOM_TXT_CDS <Q_NUMBER>
J 0
(-1403 103);
DISPLAY 1.212766 (-1403 103);
FORCEPROP 1 LAST CUSTOM_TXT_CDS <Q_PROJ>
J 0
(-2382 102);
DISPLAY 1.212766 (-2382 102);
FORCEPROP 1 LAST CUSTOM_TXT_CDS <Q_REV>
J 0
(-184 103);
DISPLAY 1.212766 (-184 103);
FORCEPROP 1 LAST CUSTOM_TXT_CDS <CON_PAGE_NUM> OF <CON_TOTAL_PAGES>
J 0
(-446 18);
DISPLAY 0.978723 (-446 18);
FORCEPROP 1 LAST Q_TITLE SMBUS - RETIMER EEPROM
J 0
(-9366 26);
DISPLAY 2.446809 (-9366 26);
PAINT GREEN (-9366 26);
FORCEPROP 2 LAST PAGE_BORDER TRUE
J 0
(-7890 5250);
DISPLAY 0.638298 (-7890 5250);
PAINT PINK (-7890 5250);
DISPLAY INVISIBLE (-7890 5250);
FORCEPROP 1 LAST CDS_LMAN_SYM_OUTLINE -9475,6775,100,-125
J 0
(0 0);
DISPLAY 0.468085 (0 0);
PAINT GREEN (0 0);
DISPLAY INVISIBLE (0 0);
FORCEPROP 2 LAST CDS_LIB pure_quanta
J 0
(0 0);
DISPLAY INVISIBLE (0 0);
FORCEPROP 2 LAST CDS_XR_PAGE_TITLE CR-185 : @T6G_MB_LIB.T6G(SCH_1):PAGE185
J 0
(-7890 5250);
DISPLAY 0.638298 (-7890 5250);
PAINT PINK (-7890 5250);
DISPLAY INVISIBLE (-7890 5250);
FORCEPROP 1 LAST Q_DEPT BU9
J 1
(-3763 49);
DISPLAY 1.957447 (-3763 49);
PAINT GREEN (-3763 49);
DISPLAY INVISIBLE (-3763 49);
FORCEPROP 1 LAST COMMENT_BODY TRUE
J 0
(12 -13);
DISPLAY 0.978723 (12 -13);
PAINT GREEN (12 -13);
DISPLAY INVISIBLE (12 -13);
FORCEADD DNS..1
(-8450 1975);
PAINT RED (-8450 1975);
FORCEPROP 2 LAST CDS_LIB mstr_misc
J 0
(-8450 1975);
DISPLAY INVISIBLE (-8450 1975);
FORCEPROP 1 LAST COMMENT_BODY TRUE
R 1
J 0
(-8375 1750);
DISPLAY 0.872340 (-8375 1750);
PAINT GREEN (-8375 1750);
DISPLAY INVISIBLE (-8375 1750);
FORCEADD DNS..1
(-8100 1950);
PAINT RED (-8100 1950);
FORCEPROP 2 LAST CDS_LIB mstr_misc
J 0
(-8100 1950);
DISPLAY INVISIBLE (-8100 1950);
FORCEPROP 1 LAST COMMENT_BODY TRUE
R 1
J 0
(-8025 1725);
DISPLAY 0.872340 (-8025 1725);
PAINT GREEN (-8025 1725);
DISPLAY INVISIBLE (-8025 1725);
WIRE 16 -1 (-7750 3200)(-7750 2975);
WIRE 16 -1 (-4475 5000)(-4175 5000);
WIRE 16 -1 (-4175 5000)(-4175 4875);
WIRE 16 -1 (-5575 6100)(-5575 5950);
WIRE 16 -1 (-3950 3675)(-5625 3675);
FORCEPROP 2 LAST SIG_NAME SMB_RT_CPU0_P0_ROM_MUX_1D_SDA
J 0
(-4835 3685);
DISPLAY 0.553191 (-4835 3685);
PAINT YELLOW (-4835 3685);
WIRE 16 -1 (-3950 3575)(-5625 3575);
FORCEPROP 2 LAST SIG_NAME SMB_RT_CPU0_P1_ROM_MUX_1D_SDA
J 0
(-4835 3585);
DISPLAY 0.553191 (-4835 3585);
PAINT YELLOW (-4835 3585);
WIRE 16 -1 (-3950 3475)(-5625 3475);
FORCEPROP 2 LAST SIG_NAME SMB_RT_CPU0_P3_ROM_MUX_1D_SDA
J 0
(-4835 3485);
DISPLAY 0.553191 (-4835 3485);
PAINT YELLOW (-4835 3485);
WIRE 16 -1 (-3950 3425)(-5625 3425);
FORCEPROP 2 LAST SIG_NAME SMB_RT_CPU0_P3_ROM_MUX_1D_SCL
J 0
(-4835 3435);
DISPLAY 0.553191 (-4835 3435);
PAINT YELLOW (-4835 3435);
WIRE 16 -1 (-2675 3650)(-3200 3650);
WIRE 16 -1 (-3200 3950)(-3200 3650);
WIRE 16 -1 (-3200 3650)(-3200 3600);
WIRE 16 -1 (-2675 3600)(-3200 3600);
WIRE 16 -1 (-3200 3600)(-3200 3550);
WIRE 16 -1 (-2675 3550)(-3200 3550);
WIRE 16 -1 (-3200 3550)(-3200 3500);
WIRE 16 -1 (-2675 3500)(-3200 3500);
WIRE 16 -1 (-3200 3500)(-3200 3450);
WIRE 16 -1 (-2675 3450)(-3200 3450);
WIRE 16 -1 (-3200 3450)(-3200 3400);
WIRE 16 -1 (-2675 3400)(-3200 3400);
WIRE 16 -1 (-3200 3400)(-3200 3350);
WIRE 16 -1 (-2675 3350)(-3200 3350);
WIRE 16 -1 (-3200 3350)(-3200 3300);
WIRE 16 -1 (-3200 3300)(-2675 3300);
WIRE 16 -1 (-825 2475)(-2300 2475);
FORCEPROP 2 LAST SIG_NAME SMB_RT_CPU1_P1_ROM_MUX_2D_R_SCL
J 0
(-1710 2475);
DISPLAY 0.553191 (-1710 2475);
PAINT YELLOW (-1710 2475);
WIRE 16 -1 (-750 3300)(-2475 3300);
FORCEPROP 2 LAST SIG_NAME SMB_RT_CPU1_P2_ROM_MUX_1D_SCL
J 0
(-1735 3310);
DISPLAY 0.553191 (-1735 3310);
PAINT YELLOW (-1735 3310);
WIRE 16 -1 (-750 3350)(-2475 3350);
FORCEPROP 2 LAST SIG_NAME SMB_RT_CPU1_P2_ROM_MUX_1D_SDA
J 0
(-1735 3360);
DISPLAY 0.553191 (-1735 3360);
PAINT YELLOW (-1735 3360);
WIRE 16 -1 (-4000 2650)(-5450 2650);
FORCEPROP 2 LAST SIG_NAME SMB_RT_CPU0_P0_ROM_MUX_2D_R_SDA
J 0
(-4860 2650);
DISPLAY 0.553191 (-4860 2650);
PAINT YELLOW (-4860 2650);
WIRE 16 -1 (-5825 3675)(-6325 3675);
WIRE 16 -1 (-6325 3900)(-6325 3675);
WIRE 16 -1 (-6325 3675)(-6325 3625);
WIRE 16 -1 (-5825 3625)(-6325 3625);
WIRE 16 -1 (-6325 3625)(-6325 3575);
WIRE 16 -1 (-5825 3575)(-6325 3575);
WIRE 16 -1 (-6325 3575)(-6325 3525);
WIRE 16 -1 (-5825 3525)(-6325 3525);
WIRE 16 -1 (-6325 3525)(-6325 3475);
WIRE 16 -1 (-5825 3475)(-6325 3475);
WIRE 16 -1 (-6325 3475)(-6325 3425);
WIRE 16 -1 (-5825 3425)(-6325 3425);
WIRE 16 -1 (-6325 3425)(-6325 3375);
WIRE 16 -1 (-5825 3375)(-6325 3375);
WIRE 16 -1 (-6325 3375)(-6325 3325);
WIRE 16 -1 (-6325 3325)(-5825 3325);
WIRE 16 -1 (-3950 3525)(-5625 3525);
FORCEPROP 2 LAST SIG_NAME SMB_RT_CPU0_P1_ROM_MUX_1D_SCL
J 0
(-4835 3535);
DISPLAY 0.553191 (-4835 3535);
PAINT YELLOW (-4835 3535);
WIRE 16 -1 (-3950 3325)(-5625 3325);
FORCEPROP 2 LAST SIG_NAME SMB_RT_CPU0_P2_ROM_MUX_1D_SCL
J 0
(-4835 3335);
DISPLAY 0.553191 (-4835 3335);
PAINT YELLOW (-4835 3335);
WIRE 16 -1 (-5650 2650)(-6150 2650);
WIRE 16 -1 (-6150 2650)(-6150 2600);
WIRE 16 -1 (-6150 2875)(-6150 2650);
WIRE 16 -1 (-5650 2600)(-6150 2600);
WIRE 16 -1 (-6150 2600)(-6150 2550);
WIRE 16 -1 (-5650 2550)(-6150 2550);
WIRE 16 -1 (-6150 2550)(-6150 2500);
WIRE 16 -1 (-5650 2500)(-6150 2500);
WIRE 16 -1 (-6150 2500)(-6150 2450);
WIRE 16 -1 (-5650 2450)(-6150 2450);
WIRE 16 -1 (-6150 2450)(-6150 2400);
WIRE 16 -1 (-5650 2400)(-6150 2400);
WIRE 16 -1 (-6150 2400)(-6150 2350);
WIRE 16 -1 (-5650 2350)(-6150 2350);
WIRE 16 -1 (-6150 2350)(-6150 2300);
WIRE 16 -1 (-6150 2300)(-5650 2300);
WIRE 16 -1 (-4000 2600)(-5450 2600);
FORCEPROP 2 LAST SIG_NAME SMB_RT_CPU0_P0_ROM_MUX_2D_R_SCL
J 0
(-4860 2600);
DISPLAY 0.553191 (-4860 2600);
PAINT YELLOW (-4860 2600);
WIRE 16 -1 (-3025 2275)(-2500 2275);
WIRE 16 -1 (-3025 2325)(-3025 2275);
WIRE 16 -1 (-2500 2325)(-3025 2325);
WIRE 16 -1 (-3025 2375)(-3025 2325);
WIRE 16 -1 (-2500 2375)(-3025 2375);
WIRE 16 -1 (-3025 2425)(-3025 2375);
WIRE 16 -1 (-2500 2425)(-3025 2425);
WIRE 16 -1 (-3025 2475)(-3025 2425);
WIRE 16 -1 (-2500 2475)(-3025 2475);
WIRE 16 -1 (-3025 2525)(-3025 2475);
WIRE 16 -1 (-2500 2525)(-3025 2525);
WIRE 16 -1 (-3025 2575)(-3025 2525);
WIRE 16 -1 (-2500 2575)(-3025 2575);
WIRE 16 -1 (-3025 2625)(-3025 2575);
WIRE 16 -1 (-2500 2625)(-3025 2625);
WIRE 16 -1 (-3025 2925)(-3025 2625);
WIRE 16 -1 (-750 3400)(-2475 3400);
FORCEPROP 2 LAST SIG_NAME SMB_RT_CPU1_P3_ROM_MUX_1D_SCL
J 0
(-1735 3410);
DISPLAY 0.553191 (-1735 3410);
PAINT YELLOW (-1735 3410);
WIRE 16 -1 (-7875 1200)(-7875 1025);
WIRE 16 -1 (-7875 1025)(-8225 1025);
WIRE 16 -1 (-8225 1200)(-8225 1025);
WIRE 16 -1 (-8225 1025)(-8525 1025);
WIRE 16 -1 (-8525 1200)(-8525 1025);
WIRE 16 -1 (-8525 1025)(-8525 925);
WIRE 16 -1 (-6400 1800)(-5975 1800);
WIRE 16 -1 (-6400 2050)(-6400 1800);
WIRE 16 -1 (-6400 1800)(-6400 1700);
WIRE 16 -1 (-6400 1700)(-5975 1700);
WIRE 16 -1 (-6400 1700)(-6400 1625);
WIRE 16 -1 (-6400 1625)(-5975 1625);
WIRE 16 -1 (-6400 1550)(-6400 1625);
WIRE 16 -1 (-6400 1550)(-5975 1550);
WIRE 16 -1 (-6400 1550)(-6400 1450);
WIRE 16 -1 (-6400 1450)(-5975 1450);
WIRE 16 -1 (-6400 1450)(-6400 1375);
WIRE 16 -1 (-6400 1375)(-5975 1375);
WIRE 16 -1 (-6400 1375)(-6400 1300);
WIRE 16 -1 (-6400 1300)(-5975 1300);
WIRE 16 -1 (-6400 1300)(-6400 1225);
WIRE 16 -1 (-6400 1225)(-5975 1225);
WIRE 16 -1 (-5400 6400)(-5400 6375);
WIRE 16 -1 (-5575 6375)(-5400 6375);
WIRE 16 -1 (-5400 6375)(-5400 5850);
WIRE 16 -1 (-5400 5850)(-5175 5850);
WIRE 16 -1 (-5575 6300)(-5575 6375);
WIRE 16 -1 (-3075 1725)(-2650 1725);
WIRE 16 -1 (-3075 1975)(-3075 1725);
WIRE 16 -1 (-3075 1725)(-3075 1625);
WIRE 16 -1 (-3075 1625)(-2650 1625);
WIRE 16 -1 (-3075 1625)(-3075 1550);
WIRE 16 -1 (-3075 1550)(-2650 1550);
WIRE 16 -1 (-3075 1475)(-3075 1550);
WIRE 16 -1 (-3075 1475)(-2650 1475);
WIRE 16 -1 (-3075 1475)(-3075 1375);
WIRE 16 -1 (-3075 1375)(-2650 1375);
WIRE 16 -1 (-3075 1375)(-3075 1300);
WIRE 16 -1 (-3075 1300)(-2650 1300);
WIRE 16 -1 (-3075 1300)(-3075 1225);
WIRE 16 -1 (-3075 1225)(-2650 1225);
WIRE 16 -1 (-3075 1225)(-3075 1150);
WIRE 16 -1 (-3075 1150)(-2650 1150);
WIRE 16 -1 (-8225 2400)(-7875 2400);
WIRE 16 -1 (-8225 2400)(-8225 2175);
WIRE 16 -1 (-8525 2400)(-8225 2400);
WIRE 16 -1 (-7875 2400)(-7875 2150);
WIRE 16 -1 (-8525 2175)(-8525 2400);
WIRE 16 -1 (-8525 2400)(-8525 2450);
WIRE 16 -1 (-750 3650)(-2475 3650);
FORCEPROP 2 LAST SIG_NAME SMB_RT_CPU1_P0_ROM_MUX_1D_SDA
J 0
(-1735 3660);
DISPLAY 0.553191 (-1735 3660);
PAINT YELLOW (-1735 3660);
WIRE 16 -1 (-750 3600)(-2475 3600);
FORCEPROP 2 LAST SIG_NAME SMB_RT_CPU1_P0_ROM_MUX_1D_SCL
J 0
(-1735 3610);
DISPLAY 0.553191 (-1735 3610);
PAINT YELLOW (-1735 3610);
WIRE 16 -1 (-750 3550)(-2475 3550);
FORCEPROP 2 LAST SIG_NAME SMB_RT_CPU1_P1_ROM_MUX_1D_SDA
J 0
(-1735 3560);
DISPLAY 0.553191 (-1735 3560);
PAINT YELLOW (-1735 3560);
WIRE 16 -1 (-750 3500)(-2475 3500);
FORCEPROP 2 LAST SIG_NAME SMB_RT_CPU1_P1_ROM_MUX_1D_SCL
J 0
(-1735 3510);
DISPLAY 0.553191 (-1735 3510);
PAINT YELLOW (-1735 3510);
WIRE 16 -1 (-750 3450)(-2475 3450);
FORCEPROP 2 LAST SIG_NAME SMB_RT_CPU1_P3_ROM_MUX_1D_SDA
J 0
(-1735 3460);
DISPLAY 0.553191 (-1735 3460);
PAINT YELLOW (-1735 3460);
WIRE 16 -1 (-3950 3625)(-5625 3625);
FORCEPROP 2 LAST SIG_NAME SMB_RT_CPU0_P0_ROM_MUX_1D_SCL
J 0
(-4835 3635);
DISPLAY 0.553191 (-4835 3635);
PAINT YELLOW (-4835 3635);
WIRE 16 -1 (-3950 3375)(-5625 3375);
FORCEPROP 2 LAST SIG_NAME SMB_RT_CPU0_P2_ROM_MUX_1D_SDA
J 0
(-4835 3385);
DISPLAY 0.553191 (-4835 3385);
PAINT YELLOW (-4835 3385);
WIRE 16 -1 (-4000 2300)(-5450 2300);
FORCEPROP 2 LAST SIG_NAME SMB_RT_CPU0_P2_ROM_MUX_2D_R_SCL
J 0
(-4860 2300);
DISPLAY 0.553191 (-4860 2300);
PAINT YELLOW (-4860 2300);
WIRE 16 -1 (-5775 1700)(-4075 1700);
FORCEPROP 2 LAST SIG_NAME SMB_RT_CPU0_P0_ROM_R_SCL
J 0
(-4860 1710);
DISPLAY 0.680851 (-4860 1710);
PAINT YELLOW (-4860 1710);
WIRE 16 -1 (-5775 1800)(-4075 1800);
FORCEPROP 2 LAST SIG_NAME SMB_RT_CPU0_P0_ROM_R_SDA
J 0
(-4860 1810);
DISPLAY 0.680851 (-4860 1810);
PAINT YELLOW (-4860 1810);
WIRE 16 -1 (-4000 2400)(-5450 2400);
FORCEPROP 2 LAST SIG_NAME SMB_RT_CPU0_P3_ROM_MUX_2D_R_SCL
J 0
(-4860 2400);
DISPLAY 0.553191 (-4860 2400);
PAINT YELLOW (-4860 2400);
WIRE 16 -1 (-825 2575)(-2300 2575);
FORCEPROP 2 LAST SIG_NAME SMB_RT_CPU1_P0_ROM_MUX_2D_R_SCL
J 0
(-1710 2575);
DISPLAY 0.553191 (-1710 2575);
PAINT YELLOW (-1710 2575);
WIRE 16 -1 (-825 2625)(-2300 2625);
FORCEPROP 2 LAST SIG_NAME SMB_RT_CPU1_P0_ROM_MUX_2D_R_SDA
J 0
(-1710 2625);
DISPLAY 0.553191 (-1710 2625);
PAINT YELLOW (-1710 2625);
WIRE 16 -1 (-825 2375)(-2300 2375);
FORCEPROP 2 LAST SIG_NAME SMB_RT_CPU1_P3_ROM_MUX_2D_R_SCL
J 0
(-1710 2375);
DISPLAY 0.553191 (-1710 2375);
PAINT YELLOW (-1710 2375);
WIRE 16 -1 (-825 2425)(-2300 2425);
FORCEPROP 2 LAST SIG_NAME SMB_RT_CPU1_P3_ROM_MUX_2D_R_SDA
J 0
(-1710 2425);
DISPLAY 0.553191 (-1710 2425);
PAINT YELLOW (-1710 2425);
WIRE 16 -1 (-825 2525)(-2300 2525);
FORCEPROP 2 LAST SIG_NAME SMB_RT_CPU1_P1_ROM_MUX_2D_R_SDA
J 0
(-1710 2525);
DISPLAY 0.553191 (-1710 2525);
PAINT YELLOW (-1710 2525);
WIRE 16 -1 (-825 2325)(-2300 2325);
FORCEPROP 2 LAST SIG_NAME SMB_RT_CPU1_P2_ROM_MUX_2D_R_SDA
J 0
(-1710 2325);
DISPLAY 0.553191 (-1710 2325);
PAINT YELLOW (-1710 2325);
WIRE 16 -1 (-825 2275)(-2300 2275);
FORCEPROP 2 LAST SIG_NAME SMB_RT_CPU1_P2_ROM_MUX_2D_R_SCL
J 0
(-1710 2275);
DISPLAY 0.553191 (-1710 2275);
PAINT YELLOW (-1710 2275);
WIRE 16 -1 (-4000 2450)(-5450 2450);
FORCEPROP 2 LAST SIG_NAME SMB_RT_CPU0_P3_ROM_MUX_2D_R_SDA
J 0
(-4860 2450);
DISPLAY 0.553191 (-4860 2450);
PAINT YELLOW (-4860 2450);
WIRE 16 -1 (-4000 2350)(-5450 2350);
FORCEPROP 2 LAST SIG_NAME SMB_RT_CPU0_P2_ROM_MUX_2D_R_SDA
J 0
(-4860 2350);
DISPLAY 0.553191 (-4860 2350);
PAINT YELLOW (-4860 2350);
WIRE 16 -1 (-4000 2500)(-5450 2500);
FORCEPROP 2 LAST SIG_NAME SMB_RT_CPU0_P1_ROM_MUX_2D_R_SCL
J 0
(-4860 2500);
DISPLAY 0.553191 (-4860 2500);
PAINT YELLOW (-4860 2500);
WIRE 16 -1 (-4000 2550)(-5450 2550);
FORCEPROP 2 LAST SIG_NAME SMB_RT_CPU0_P1_ROM_MUX_2D_R_SDA
J 0
(-4860 2550);
DISPLAY 0.553191 (-4860 2550);
PAINT YELLOW (-4860 2550);
WIRE 16 -1 (-5175 5100)(-6325 5100);
FORCEPROP 2 LAST SIG_NAME SMB_RT_CPU1_P2_ROM_MUX_2D_R_SCL
J 0
(-6060 5110);
DISPLAY 0.553191 (-6060 5110);
PAINT YELLOW (-6060 5110);
FORCEPROP 2 LASTPROP $XR0 185 
J 0
(-6330 5110);
DISPLAY 0.638298 (-6330 5110);
PAINT MONO (-6330 5110);
WIRE 16 -1 (-6725 5550)(-8075 5550);
FORCEPROP 2 LAST SIG_NAME RST_SMB_RT_ROM_R1_N
J 0
(-7810 5560);
DISPLAY 0.680851 (-7810 5560);
PAINT YELLOW (-7810 5560);
WIRE 16 -1 (-6525 5150)(-7875 5150);
FORCEPROP 2 LAST SIG_NAME SMB_RT_CPU1_P2_ROM_MUX_2D_SDA
J 0
(-7860 5160);
DISPLAY 0.553191 (-7860 5160);
PAINT YELLOW (-7860 5160);
WIRE 16 -1 (-6525 5100)(-7900 5100);
FORCEPROP 2 LAST SIG_NAME SMB_RT_CPU1_P2_ROM_MUX_2D_SCL
J 0
(-7860 5110);
DISPLAY 0.553191 (-7860 5110);
PAINT YELLOW (-7860 5110);
WIRE 16 -1 (-6525 5200)(-7900 5200);
FORCEPROP 2 LAST SIG_NAME SMB_RT_CPU1_P3_ROM_MUX_2D_SCL
J 0
(-7860 5210);
DISPLAY 0.553191 (-7860 5210);
PAINT YELLOW (-7860 5210);
WIRE 16 -1 (-6525 5300)(-7900 5300);
FORCEPROP 2 LAST SIG_NAME SMB_RT_CPU1_P1_ROM_MUX_2D_SCL
J 0
(-7860 5310);
DISPLAY 0.553191 (-7860 5310);
PAINT YELLOW (-7860 5310);
WIRE 16 -1 (-6525 5250)(-7875 5250);
FORCEPROP 2 LAST SIG_NAME SMB_RT_CPU1_P3_ROM_MUX_2D_SDA
J 0
(-7860 5260);
DISPLAY 0.553191 (-7860 5260);
PAINT YELLOW (-7860 5260);
WIRE 16 -1 (-6525 5350)(-7875 5350);
FORCEPROP 2 LAST SIG_NAME SMB_RT_CPU1_P1_ROM_MUX_2D_SDA
J 0
(-7860 5360);
DISPLAY 0.553191 (-7860 5360);
PAINT YELLOW (-7860 5360);
WIRE 16 -1 (-6525 5400)(-7900 5400);
FORCEPROP 2 LAST SIG_NAME SMB_RT_CPU1_P0_ROM_MUX_2D_SCL
J 0
(-7860 5410);
DISPLAY 0.553191 (-7860 5410);
PAINT YELLOW (-7860 5410);
WIRE 16 -1 (-6525 5450)(-7875 5450);
FORCEPROP 2 LAST SIG_NAME SMB_RT_CPU1_P0_ROM_MUX_2D_SDA
J 0
(-7860 5460);
DISPLAY 0.553191 (-7860 5460);
PAINT YELLOW (-7860 5460);
WIRE 16 -1 (-5175 5550)(-6525 5550);
FORCEPROP 2 LAST SIG_NAME RST_SMB_RT_ROM_N
J 0
(-6010 5560);
DISPLAY 0.680851 (-6010 5560);
PAINT YELLOW (-6010 5560);
FORCEPROP 2 LASTPROP $XRERR UNIQUE?
J 0
(-6250 5560);
DISPLAY 0.638298 (-6250 5560);
PAINT MONO (-6250 5560);
DISPLAY INVISIBLE (-6250 5560);
WIRE 16 -1 (-5175 5150)(-6325 5150);
FORCEPROP 2 LAST SIG_NAME SMB_RT_CPU1_P2_ROM_MUX_2D_R_SDA
J 0
(-6060 5160);
DISPLAY 0.553191 (-6060 5160);
PAINT YELLOW (-6060 5160);
FORCEPROP 2 LASTPROP $XR0 185 
J 0
(-6330 5160);
DISPLAY 0.638298 (-6330 5160);
PAINT MONO (-6330 5160);
WIRE 16 -1 (-5175 5300)(-6325 5300);
FORCEPROP 2 LAST SIG_NAME SMB_RT_CPU1_P1_ROM_MUX_2D_R_SCL
J 0
(-6060 5310);
DISPLAY 0.553191 (-6060 5310);
PAINT YELLOW (-6060 5310);
FORCEPROP 2 LASTPROP $XR0 185 
J 0
(-6330 5310);
DISPLAY 0.638298 (-6330 5310);
PAINT MONO (-6330 5310);
WIRE 16 -1 (-5175 5250)(-6325 5250);
FORCEPROP 2 LAST SIG_NAME SMB_RT_CPU1_P3_ROM_MUX_2D_R_SDA
J 0
(-6060 5260);
DISPLAY 0.553191 (-6060 5260);
PAINT YELLOW (-6060 5260);
FORCEPROP 2 LASTPROP $XR0 185 
J 0
(-6330 5260);
DISPLAY 0.638298 (-6330 5260);
PAINT MONO (-6330 5260);
WIRE 16 -1 (-5175 5200)(-6325 5200);
FORCEPROP 2 LAST SIG_NAME SMB_RT_CPU1_P3_ROM_MUX_2D_R_SCL
J 0
(-6060 5210);
DISPLAY 0.553191 (-6060 5210);
PAINT YELLOW (-6060 5210);
FORCEPROP 2 LASTPROP $XR0 185 
J 0
(-6330 5210);
DISPLAY 0.638298 (-6330 5210);
PAINT MONO (-6330 5210);
WIRE 16 -1 (-5175 5350)(-6325 5350);
FORCEPROP 2 LAST SIG_NAME SMB_RT_CPU1_P1_ROM_MUX_2D_R_SDA
J 0
(-6060 5360);
DISPLAY 0.553191 (-6060 5360);
PAINT YELLOW (-6060 5360);
FORCEPROP 2 LASTPROP $XR0 185 
J 0
(-6330 5360);
DISPLAY 0.638298 (-6330 5360);
PAINT MONO (-6330 5360);
WIRE 16 -1 (-5175 5400)(-6325 5400);
FORCEPROP 2 LAST SIG_NAME SMB_RT_CPU1_P0_ROM_MUX_2D_R_SCL
J 0
(-6060 5410);
DISPLAY 0.553191 (-6060 5410);
PAINT YELLOW (-6060 5410);
FORCEPROP 2 LASTPROP $XR0 185 
J 0
(-6330 5410);
DISPLAY 0.638298 (-6330 5410);
PAINT MONO (-6330 5410);
WIRE 16 -1 (-5175 5450)(-6325 5450);
FORCEPROP 2 LAST SIG_NAME SMB_RT_CPU1_P0_ROM_MUX_2D_R_SDA
J 0
(-6060 5460);
DISPLAY 0.553191 (-6060 5460);
PAINT YELLOW (-6060 5460);
FORCEPROP 2 LASTPROP $XR0 185 
J 0
(-6330 5460);
DISPLAY 0.638298 (-6330 5460);
PAINT MONO (-6330 5460);
WIRE 16 -1 (-5175 5650)(-6125 5650);
FORCEPROP 2 LAST SIG_NAME RT_ROM_SMB_MUX_ADDR2
J 0
(-6010 5660);
DISPLAY 0.680851 (-6010 5660);
PAINT YELLOW (-6010 5660);
WIRE 16 -1 (-5175 5700)(-6125 5700);
FORCEPROP 2 LAST SIG_NAME RT_ROM_SMB_MUX_ADDR1
J 0
(-6010 5710);
DISPLAY 0.680851 (-6010 5710);
PAINT YELLOW (-6010 5710);
WIRE 16 -1 (-5175 5750)(-6125 5750);
FORCEPROP 2 LAST SIG_NAME RT_ROM_SMB_MUX_ADDR0
J 0
(-6010 5760);
DISPLAY 0.680851 (-6010 5760);
PAINT YELLOW (-6010 5760);
WIRE 16 -1 (-2925 5650)(-1675 5650);
FORCEPROP 2 LAST SIG_NAME SMB_MUX_RT_ROM_R1_SCL
J 0
(-2460 5660);
DISPLAY 0.680851 (-2460 5660);
PAINT YELLOW (-2460 5660);
WIRE 16 -1 (-4475 5650)(-3125 5650);
FORCEPROP 2 LAST SIG_NAME SMB_MUX_RT_ROM_SCL
J 0
(-4185 5660);
DISPLAY 0.680851 (-4185 5660);
PAINT YELLOW (-4185 5660);
FORCEPROP 2 LASTPROP $XRERR UNIQUE?
J 0
(-4425 5660);
DISPLAY 0.638298 (-4425 5660);
PAINT MONO (-4425 5660);
DISPLAY INVISIBLE (-4425 5660);
WIRE 16 -1 (-2925 5700)(-1700 5700);
FORCEPROP 2 LAST SIG_NAME SMB_MUX_RT_ROM_R1_SDA
J 0
(-2460 5710);
DISPLAY 0.680851 (-2460 5710);
PAINT YELLOW (-2460 5710);
WIRE 16 -1 (-4475 5700)(-3125 5700);
FORCEPROP 2 LAST SIG_NAME SMB_MUX_RT_ROM_SDA
J 0
(-4185 5710);
DISPLAY 0.680851 (-4185 5710);
PAINT YELLOW (-4185 5710);
FORCEPROP 2 LASTPROP $XRERR UNIQUE?
J 0
(-4425 5710);
DISPLAY 0.638298 (-4425 5710);
PAINT MONO (-4425 5710);
DISPLAY INVISIBLE (-4425 5710);
WIRE 16 -1 (-1375 5150)(-2675 5150);
FORCEPROP 2 LAST SIG_NAME SMB_RT_CPU0_P2_ROM_MUX_2D_SDA
J 0
(-2460 5160);
DISPLAY 0.680851 (-2460 5160);
PAINT YELLOW (-2460 5160);
WIRE 16 -1 (-2875 5150)(-4475 5150);
FORCEPROP 2 LAST SIG_NAME SMB_RT_CPU0_P2_ROM_MUX_2D_R_SDA
J 0
(-4210 5160);
DISPLAY 0.553191 (-4210 5160);
PAINT YELLOW (-4210 5160);
FORCEPROP 2 LASTPROP $XR0 185 
J 0
(-4336 5160);
DISPLAY 0.638298 (-4336 5160);
PAINT MONO (-4336 5160);
WIRE 16 -1 (-1375 5100)(-2675 5100);
FORCEPROP 2 LAST SIG_NAME SMB_RT_CPU0_P2_ROM_MUX_2D_SCL
J 0
(-2460 5110);
DISPLAY 0.680851 (-2460 5110);
PAINT YELLOW (-2460 5110);
WIRE 16 -1 (-2875 5100)(-4475 5100);
FORCEPROP 2 LAST SIG_NAME SMB_RT_CPU0_P2_ROM_MUX_2D_R_SCL
J 0
(-4210 5110);
DISPLAY 0.553191 (-4210 5110);
PAINT YELLOW (-4210 5110);
FORCEPROP 2 LASTPROP $XR0 185 
J 0
(-4336 5110);
DISPLAY 0.638298 (-4336 5110);
PAINT MONO (-4336 5110);
WIRE 16 -1 (-1375 5300)(-2675 5300);
FORCEPROP 2 LAST SIG_NAME SMB_RT_CPU0_P1_ROM_MUX_2D_SCL
J 0
(-2460 5310);
DISPLAY 0.680851 (-2460 5310);
PAINT YELLOW (-2460 5310);
WIRE 16 -1 (-2875 5300)(-4475 5300);
FORCEPROP 2 LAST SIG_NAME SMB_RT_CPU0_P1_ROM_MUX_2D_R_SCL
J 0
(-4210 5310);
DISPLAY 0.553191 (-4210 5310);
PAINT YELLOW (-4210 5310);
FORCEPROP 2 LASTPROP $XR0 185 
J 0
(-4336 5310);
DISPLAY 0.638298 (-4336 5310);
PAINT MONO (-4336 5310);
WIRE 16 -1 (-1375 5250)(-2675 5250);
FORCEPROP 2 LAST SIG_NAME SMB_RT_CPU0_P3_ROM_MUX_2D_SDA
J 0
(-2460 5260);
DISPLAY 0.680851 (-2460 5260);
PAINT YELLOW (-2460 5260);
WIRE 16 -1 (-2875 5250)(-4475 5250);
FORCEPROP 2 LAST SIG_NAME SMB_RT_CPU0_P3_ROM_MUX_2D_R_SDA
J 0
(-4210 5260);
DISPLAY 0.553191 (-4210 5260);
PAINT YELLOW (-4210 5260);
FORCEPROP 2 LASTPROP $XR0 185 
J 0
(-4336 5260);
DISPLAY 0.638298 (-4336 5260);
PAINT MONO (-4336 5260);
WIRE 16 -1 (-1350 5400)(-2675 5400);
FORCEPROP 2 LAST SIG_NAME SMB_RT_CPU0_P0_ROM_MUX_2D_SCL
J 0
(-2460 5410);
DISPLAY 0.680851 (-2460 5410);
PAINT YELLOW (-2460 5410);
WIRE 16 -1 (-2875 5400)(-4475 5400);
FORCEPROP 2 LAST SIG_NAME SMB_RT_CPU0_P0_ROM_MUX_2D_R_SCL
J 0
(-4210 5410);
DISPLAY 0.553191 (-4210 5410);
PAINT YELLOW (-4210 5410);
FORCEPROP 2 LASTPROP $XR0 185 
J 0
(-4336 5410);
DISPLAY 0.638298 (-4336 5410);
PAINT MONO (-4336 5410);
WIRE 16 -1 (-1375 5350)(-2675 5350);
FORCEPROP 2 LAST SIG_NAME SMB_RT_CPU0_P1_ROM_MUX_2D_SDA
J 0
(-2460 5360);
DISPLAY 0.680851 (-2460 5360);
PAINT YELLOW (-2460 5360);
WIRE 16 -1 (-2875 5350)(-4475 5350);
FORCEPROP 2 LAST SIG_NAME SMB_RT_CPU0_P1_ROM_MUX_2D_R_SDA
J 0
(-4210 5360);
DISPLAY 0.553191 (-4210 5360);
PAINT YELLOW (-4210 5360);
FORCEPROP 2 LASTPROP $XR0 185 
J 0
(-4336 5360);
DISPLAY 0.638298 (-4336 5360);
PAINT MONO (-4336 5360);
WIRE 16 -1 (-1375 5450)(-2675 5450);
FORCEPROP 2 LAST SIG_NAME SMB_RT_CPU0_P0_ROM_MUX_2D_SDA
J 0
(-2460 5460);
DISPLAY 0.680851 (-2460 5460);
PAINT YELLOW (-2460 5460);
WIRE 16 -1 (-2875 5450)(-4475 5450);
FORCEPROP 2 LAST SIG_NAME SMB_RT_CPU0_P0_ROM_MUX_2D_R_SDA
J 0
(-4210 5460);
DISPLAY 0.553191 (-4210 5460);
PAINT YELLOW (-4210 5460);
FORCEPROP 2 LASTPROP $XR0 185 
J 0
(-4336 5460);
DISPLAY 0.638298 (-4336 5460);
PAINT MONO (-4336 5460);
WIRE 16 -1 (-1375 5200)(-2675 5200);
FORCEPROP 2 LAST SIG_NAME SMB_RT_CPU0_P3_ROM_MUX_2D_SCL
J 0
(-2460 5210);
DISPLAY 0.680851 (-2460 5210);
PAINT YELLOW (-2460 5210);
WIRE 16 -1 (-2875 5200)(-4475 5200);
FORCEPROP 2 LAST SIG_NAME SMB_RT_CPU0_P3_ROM_MUX_2D_R_SCL
J 0
(-4210 5210);
DISPLAY 0.553191 (-4210 5210);
PAINT YELLOW (-4210 5210);
FORCEPROP 2 LASTPROP $XR0 185 
J 0
(-4336 5210);
DISPLAY 0.638298 (-4336 5210);
PAINT MONO (-4336 5210);
WIRE 16 -1 (-8400 3550)(-7750 3550);
FORCEPROP 2 LAST SIG_NAME RST_SMB_RT_ROM_R1_N
J 0
(-8210 3585);
DISPLAY 0.680851 (-8210 3585);
PAINT YELLOW (-8210 3585);
WIRE 16 -1 (-7750 3550)(-7750 3400);
WIRE 16 -1 (-5775 1550)(-4075 1550);
FORCEPROP 2 LAST SIG_NAME SMB_RT_CPU0_P1_ROM_R_SCL
J 0
(-4860 1560);
DISPLAY 0.680851 (-4860 1560);
PAINT YELLOW (-4860 1560);
WIRE 16 -1 (-5775 1625)(-4075 1625);
FORCEPROP 2 LAST SIG_NAME SMB_RT_CPU0_P1_ROM_R_SDA
J 0
(-4860 1635);
DISPLAY 0.680851 (-4860 1635);
PAINT YELLOW (-4860 1635);
WIRE 16 -1 (-2450 1725)(-750 1725);
FORCEPROP 2 LAST SIG_NAME SMB_RT_CPU1_P0_ROM_R_SDA
J 0
(-1535 1735);
DISPLAY 0.680851 (-1535 1735);
PAINT YELLOW (-1535 1735);
WIRE 16 -1 (-2450 1625)(-750 1625);
FORCEPROP 2 LAST SIG_NAME SMB_RT_CPU1_P0_ROM_R_SCL
J 0
(-1535 1635);
DISPLAY 0.680851 (-1535 1635);
PAINT YELLOW (-1535 1635);
WIRE 16 -1 (-2450 1475)(-750 1475);
FORCEPROP 2 LAST SIG_NAME SMB_RT_CPU1_P1_ROM_R_SCL
J 0
(-1535 1485);
DISPLAY 0.680851 (-1535 1485);
PAINT YELLOW (-1535 1485);
WIRE 16 -1 (-2450 1550)(-750 1550);
FORCEPROP 2 LAST SIG_NAME SMB_RT_CPU1_P1_ROM_R_SDA
J 0
(-1535 1560);
DISPLAY 0.680851 (-1535 1560);
PAINT YELLOW (-1535 1560);
WIRE 16 -1 (-5775 1450)(-4075 1450);
FORCEPROP 2 LAST SIG_NAME SMB_RT_CPU0_P3_ROM_R_SDA
J 0
(-4860 1460);
DISPLAY 0.680851 (-4860 1460);
PAINT YELLOW (-4860 1460);
WIRE 16 -1 (-5775 1300)(-4075 1300);
FORCEPROP 2 LAST SIG_NAME SMB_RT_CPU0_P2_ROM_R_SDA
J 0
(-4860 1310);
DISPLAY 0.680851 (-4860 1310);
PAINT YELLOW (-4860 1310);
WIRE 16 -1 (-5775 1225)(-4075 1225);
FORCEPROP 2 LAST SIG_NAME SMB_RT_CPU0_P2_ROM_R_SCL
J 0
(-4860 1235);
DISPLAY 0.680851 (-4860 1235);
PAINT YELLOW (-4860 1235);
WIRE 16 -1 (-5775 1375)(-4075 1375);
FORCEPROP 2 LAST SIG_NAME SMB_RT_CPU0_P3_ROM_R_SCL
J 0
(-4860 1385);
DISPLAY 0.680851 (-4860 1385);
PAINT YELLOW (-4860 1385);
WIRE 16 -1 (-7025 1750)(-8525 1750);
FORCEPROP 2 LAST SIG_NAME RT_ROM_SMB_MUX_ADDR2
J 0
(-7810 1785);
DISPLAY 0.680851 (-7810 1785);
PAINT YELLOW (-7810 1785);
WIRE 16 -1 (-8525 1975)(-8525 1750);
WIRE 16 -1 (-8525 1750)(-8525 1400);
WIRE 16 -1 (-7025 1650)(-8225 1650);
FORCEPROP 2 LAST SIG_NAME RT_ROM_SMB_MUX_ADDR1
J 0
(-7810 1660);
DISPLAY 0.680851 (-7810 1660);
PAINT YELLOW (-7810 1660);
WIRE 16 -1 (-8225 1650)(-8225 1975);
WIRE 16 -1 (-8225 1400)(-8225 1650);
WIRE 16 -1 (-7025 1550)(-7875 1550);
FORCEPROP 2 LAST SIG_NAME RT_ROM_SMB_MUX_ADDR0
J 0
(-7810 1560);
DISPLAY 0.680851 (-7810 1560);
PAINT YELLOW (-7810 1560);
WIRE 16 -1 (-7875 1550)(-7875 1950);
WIRE 16 -1 (-7875 1400)(-7875 1550);
WIRE 16 -1 (-2450 1375)(-750 1375);
FORCEPROP 2 LAST SIG_NAME SMB_RT_CPU1_P3_ROM_R_SDA
J 0
(-1535 1385);
DISPLAY 0.680851 (-1535 1385);
PAINT YELLOW (-1535 1385);
WIRE 16 -1 (-2450 1150)(-750 1150);
FORCEPROP 2 LAST SIG_NAME SMB_RT_CPU1_P2_ROM_R_SCL
J 0
(-1535 1160);
DISPLAY 0.680851 (-1535 1160);
PAINT YELLOW (-1535 1160);
WIRE 16 -1 (-2450 1225)(-750 1225);
FORCEPROP 2 LAST SIG_NAME SMB_RT_CPU1_P2_ROM_R_SDA
J 0
(-1535 1235);
DISPLAY 0.680851 (-1535 1235);
PAINT YELLOW (-1535 1235);
WIRE 16 -1 (-2450 1300)(-750 1300);
FORCEPROP 2 LAST SIG_NAME SMB_RT_CPU1_P3_ROM_R_SCL
J 0
(-1535 1310);
DISPLAY 0.680851 (-1535 1310);
PAINT YELLOW (-1535 1310);
DOT 1 (-3025 2475);
DOT 1 (-3200 3650);
DOT 1 (-3200 3600);
DOT 1 (-3200 3550);
DOT 1 (-3200 3500);
DOT 1 (-3200 3400);
DOT 1 (-3200 3350);
DOT 1 (-6325 3675);
DOT 1 (-6325 3575);
DOT 1 (-6325 3525);
DOT 1 (-6325 3475);
DOT 1 (-6325 3425);
DOT 1 (-6325 3375);
DOT 1 (-6325 3625);
DOT 1 (-5400 6375);
DOT 1 (-8525 1025);
DOT 1 (-8525 1750);
DOT 1 (-8225 1650);
DOT 1 (-8525 2400);
DOT 1 (-8225 2400);
DOT 1 (-7875 1550);
DOT 1 (-6400 1300);
DOT 1 (-6400 1375);
DOT 1 (-6400 1450);
DOT 1 (-6400 1550);
DOT 1 (-6400 1625);
DOT 1 (-6400 1700);
DOT 1 (-3075 1225);
DOT 1 (-3075 1300);
DOT 1 (-8225 1025);
DOT 1 (-6400 1800);
DOT 1 (-3075 1475);
DOT 1 (-3075 1375);
DOT 1 (-3075 1725);
DOT 1 (-3075 1625);
DOT 1 (-3075 1550);
DOT 1 (-3200 3450);
DOT 1 (-6150 2350);
DOT 1 (-6150 2400);
DOT 1 (-6150 2450);
DOT 1 (-6150 2500);
DOT 1 (-6150 2550);
DOT 1 (-6150 2600);
DOT 1 (-6150 2650);
DOT 1 (-3025 2325);
DOT 1 (-3025 2375);
DOT 1 (-3025 2425);
DOT 1 (-3025 2525);
DOT 1 (-3025 2625);
DOT 1 (-3025 2575);
FORCENOTE
TCA9548 ADDR: 0XE0 (8-BIT) /0X70 (7-BIT)
(-6525 4650) 0;
DISPLAY LEFT (-6525 4650);
DISPLAY 1.595745 (-6525 4650);
FORCENOTE
FOR RT EEPROM SIDE
(-4550 1025) 0;
DISPLAY LEFT (-4550 1025);
DISPLAY 1.021277 (-4550 1025);
FORCENOTE
FOR RT EEPROM SIDE
(-1200 1000) 0;
DISPLAY LEFT (-1200 1000);
DISPLAY 1.021277 (-1200 1000);
FORCENOTE
FOR RT I2C MUX SIDE
(-1425 2150) 0;
DISPLAY LEFT (-1425 2150);
DISPLAY 1.021277 (-1425 2150);
FORCENOTE
FOR RT I2C MUX SIDE
(-4650 2175) 0;
DISPLAY LEFT (-4650 2175);
DISPLAY 1.021277 (-4650 2175);
QUIT
